G04 ================== begin FILE IDENTIFICATION RECORD ==================*
G04 Layout Name:  9051_F0T_Panel_BD_Front_D_v02_20221209_1310.brd*
G04 Film Name:    gnd*
G04 File Format:  Gerber RS274X*
G04 File Origin:  Cadence Allegro 17.2-S081*
G04 Origin Date:  Mon Dec 12 15:51:17 2022*
G04 *
G04 Layer:  DRAWING FORMAT/TITLE_BLOCK_A*
G04 Layer:  PIN/SPECIAL_DRILL*
G04 Layer:  DRAWING FORMAT/TITLE_BLOCK*
G04 Layer:  VIA CLASS/GND*
G04 Layer:  PIN/GND*
G04 Layer:  MANUFACTURING/PHOTOPLOT_OUTLINE*
G04 Layer:  ETCH/GND*
G04 Layer:  DRAWING FORMAT/TITLE_DATA_GND*
G04 *
G04 Offset:    (0.00 0.00)*
G04 Mirror:    No*
G04 Mode:      Negative*
G04 Rotation:  0*
G04 FullContactRelief:  No*
G04 UndefLineWidth:     6.00*
G04 ================== end FILE IDENTIFICATION RECORD ====================*
%FSLAX25Y25*MOIN*%
%IR0*IPPOS*OFA0.00000B0.00000*MIA0B0*SFA1.00000B1.00000*%
%ADD13C,.03*%
%ADD12C,.052*%
%ADD33C,.071*%
%ADD24C,.082*%
%AMMACRO21*
4,1,36,.0025,0.0,
.002462,.000434,
.002349,.000855,
.002165,.00125,
.001915,.001607,
.001607,.001915,
.00125,.002165,
.000855,.002349,
.000434,.002462,
0.0,.0025,
-.000434,.002462,
-.000855,.002349,
-.00125,.002165,
-.001607,.001915,
-.001915,.001607,
-.002165,.00125,
-.002349,.000855,
-.002462,.000434,
-.0025,0.0,
-.002462,-.000434,
-.002349,-.000855,
-.002165,-.00125,
-.001915,-.001607,
-.001607,-.001915,
-.00125,-.002165,
-.000855,-.002349,
-.000434,-.002462,
0.0,-.0025,
.000434,-.002462,
.000855,-.002349,
.00125,-.002165,
.001607,-.001915,
.001915,-.001607,
.002165,-.00125,
.002349,-.000855,
.002462,-.000434,
.0025,0.0,
225.*
%
%ADD21MACRO21*%
%AMMACRO20*
4,1,36,.0025,0.0,
.002462,.000434,
.002349,.000855,
.002165,.00125,
.001915,.001607,
.001607,.001915,
.00125,.002165,
.000855,.002349,
.000434,.002462,
0.0,.0025,
-.000434,.002462,
-.000855,.002349,
-.00125,.002165,
-.001607,.001915,
-.001915,.001607,
-.002165,.00125,
-.002349,.000855,
-.002462,.000434,
-.0025,0.0,
-.002462,-.000434,
-.002349,-.000855,
-.002165,-.00125,
-.001915,-.001607,
-.001607,-.001915,
-.00125,-.002165,
-.000855,-.002349,
-.000434,-.002462,
0.0,-.0025,
.000434,-.002462,
.000855,-.002349,
.00125,-.002165,
.001607,-.001915,
.001915,-.001607,
.002165,-.00125,
.002349,-.000855,
.002462,-.000434,
.0025,0.0,
270.*
%
%ADD20MACRO20*%
%AMMACRO19*
4,1,36,.0025,0.0,
.002462,.000434,
.002349,.000855,
.002165,.00125,
.001915,.001607,
.001607,.001915,
.00125,.002165,
.000855,.002349,
.000434,.002462,
0.0,.0025,
-.000434,.002462,
-.000855,.002349,
-.00125,.002165,
-.001607,.001915,
-.001915,.001607,
-.002165,.00125,
-.002349,.000855,
-.002462,.000434,
-.0025,0.0,
-.002462,-.000434,
-.002349,-.000855,
-.002165,-.00125,
-.001915,-.001607,
-.001607,-.001915,
-.00125,-.002165,
-.000855,-.002349,
-.000434,-.002462,
0.0,-.0025,
.000434,-.002462,
.000855,-.002349,
.00125,-.002165,
.001607,-.001915,
.001915,-.001607,
.002165,-.00125,
.002349,-.000855,
.002462,-.000434,
.0025,0.0,
315.*
%
%ADD19MACRO19*%
%AMMACRO16*
4,1,36,.0025,0.0,
.002462,.000434,
.002349,.000855,
.002165,.00125,
.001915,.001607,
.001607,.001915,
.00125,.002165,
.000855,.002349,
.000434,.002462,
0.0,.0025,
-.000434,.002462,
-.000855,.002349,
-.00125,.002165,
-.001607,.001915,
-.001915,.001607,
-.002165,.00125,
-.002349,.000855,
-.002462,.000434,
-.0025,0.0,
-.002462,-.000434,
-.002349,-.000855,
-.002165,-.00125,
-.001915,-.001607,
-.001607,-.001915,
-.00125,-.002165,
-.000855,-.002349,
-.000434,-.002462,
0.0,-.0025,
.000434,-.002462,
.000855,-.002349,
.00125,-.002165,
.001607,-.001915,
.001915,-.001607,
.002165,-.00125,
.002349,-.000855,
.002462,-.000434,
.0025,0.0,
180.*
%
%ADD16MACRO16*%
%AMMACRO38*
4,1,36,.003,0.0,
.002954,.000521,
.002819,.001026,
.002598,.0015,
.002298,.001928,
.001928,.002298,
.0015,.002598,
.001026,.002819,
.000521,.002954,
0.0,.003,
-.000521,.002954,
-.001026,.002819,
-.0015,.002598,
-.001928,.002298,
-.002298,.001928,
-.002598,.0015,
-.002819,.001026,
-.002954,.000521,
-.003,0.0,
-.002954,-.000521,
-.002819,-.001026,
-.002598,-.0015,
-.002298,-.001928,
-.001928,-.002298,
-.0015,-.002598,
-.001026,-.002819,
-.000521,-.002954,
0.0,-.003,
.000521,-.002954,
.001026,-.002819,
.0015,-.002598,
.001928,-.002298,
.002298,-.001928,
.002598,-.0015,
.002819,-.001026,
.002954,-.000521,
.003,0.0,
270.*
%
%ADD38MACRO38*%
%AMMACRO35*
4,1,36,-.0025,0.0,
-.002462,.000434,
-.002349,.000855,
-.002165,.00125,
-.001915,.001607,
-.001607,.001915,
-.00125,.002165,
-.000855,.002349,
-.000434,.002462,
0.0,.0025,
.000434,.002462,
.000855,.002349,
.00125,.002165,
.001607,.001915,
.001915,.001607,
.002165,.00125,
.002349,.000855,
.002462,.000434,
.0025,0.0,
.002462,-.000434,
.002349,-.000855,
.002165,-.00125,
.001915,-.001607,
.001607,-.001915,
.00125,-.002165,
.000855,-.002349,
.000434,-.002462,
0.0,-.0025,
-.000434,-.002462,
-.000855,-.002349,
-.00125,-.002165,
-.001607,-.001915,
-.001915,-.001607,
-.002165,-.00125,
-.002349,-.000855,
-.002462,-.000434,
-.0025,0.0,
270.*
%
%ADD35MACRO35*%
%ADD37C,.0435*%
%ADD27C,.048*%
%ADD22C,.058*%
%ADD30C,.087*%
%AMMACRO25*
4,1,13,.01917,.00857,
.020367,.005111,
.020945,.001497,
.020887,-.002163,
.020194,-.005757,
.01917,-.00857,
.02438,-.01377,
.026401,-.009327,
.027619,-.004601,
.027999,.000265,
.027527,.005123,
.02622,.009825,
.02438,.01377,
.01917,.00857,
0.0*
4,1,13,.00857,-.01917,
.005111,-.020367,
.001497,-.020945,
-.002163,-.020887,
-.005757,-.020194,
-.00857,-.01917,
-.01377,-.02438,
-.009327,-.026401,
-.004601,-.027619,
.000265,-.027999,
.005123,-.027527,
.009825,-.02622,
.01377,-.02438,
.00857,-.01917,
0.0*
4,1,13,-.01917,-.00857,
-.020367,-.005111,
-.020945,-.001497,
-.020887,.002163,
-.020194,.005757,
-.01917,.00857,
-.02438,.01377,
-.026401,.009327,
-.027619,.004601,
-.027999,-.000265,
-.027527,-.005123,
-.02622,-.009825,
-.02438,-.01377,
-.01917,-.00857,
0.0*
4,1,13,-.00857,.01917,
-.005111,.020367,
-.001497,.020945,
.002163,.020887,
.005757,.020194,
.00857,.01917,
.01377,.02438,
.009327,.026401,
.004601,.027619,
-.000265,.027999,
-.005123,.027527,
-.009825,.02622,
-.01377,.02438,
-.00857,.01917,
0.0*
%
%ADD25MACRO25*%
%AMMACRO28*
4,1,15,.01993,.00932,
.021246,.005718,
.021916,.001941,
.02192,-.001894,
.021258,-.005671,
.01995,-.009276,
.01993,-.00932,
.02511,-.01451,
.027248,-.009929,
.028558,-.005047,
.029001,-.000011,
.028562,.005025,
.027256,.009909,
.025121,.014491,
.02511,.01451,
.01993,.00932,
0.0*
4,1,15,.00932,-.01993,
.005718,-.021246,
.001941,-.021916,
-.001894,-.02192,
-.005671,-.021258,
-.009276,-.01995,
-.00932,-.01993,
-.01451,-.02511,
-.009929,-.027248,
-.005047,-.028558,
-.000011,-.029001,
.005025,-.028562,
.009909,-.027256,
.014491,-.025121,
.01451,-.02511,
.00932,-.01993,
0.0*
4,1,15,-.01993,-.00932,
-.021246,-.005718,
-.021916,-.001941,
-.02192,.001894,
-.021258,.005671,
-.01995,.009276,
-.01993,.00932,
-.02511,.01451,
-.027248,.009929,
-.028558,.005047,
-.029001,.000011,
-.028562,-.005025,
-.027256,-.009909,
-.025121,-.014491,
-.02511,-.01451,
-.01993,-.00932,
0.0*
4,1,15,-.00932,.01993,
-.005718,.021246,
-.001941,.021916,
.001894,.02192,
.005671,.021258,
.009276,.01995,
.00932,.01993,
.01451,.02511,
.009929,.027248,
.005047,.028558,
.000011,.029001,
-.005025,.028562,
-.009909,.027256,
-.014491,.025121,
-.01451,.02511,
-.00932,.01993,
0.0*
%
%ADD28MACRO28*%
%AMMACRO26*
4,1,20,-.0075,-.05558,
-.012609,-.05382,
-.017336,-.0512,
-.021535,-.047799,
-.02508,-.043721,
-.027863,-.039089,
-.029799,-.034044,
-.03083,-.028739,
-.031,-.0255,
-.031,-.0075,
-.024,-.0075,
-.024,-.0255,
-.023635,-.029668,
-.022552,-.033709,
-.020784,-.037501,
-.018384,-.040929,
-.015426,-.043887,
-.011999,-.046287,
-.008207,-.048055,
-.0075,-.0483,
-.0075,-.05558,
0.0*
4,1,20,.0075,-.05558,
.0075,-.0483,
.011345,-.046651,
.014846,-.044359,
.017895,-.041494,
.0204,-.038143,
.022286,-.034408,
.023494,-.030402,
.023988,-.026248,
.024,-.0255,
.024,-.0075,
.031,-.0075,
.031,-.0255,
.030529,-.030883,
.02913,-.036103,
.026847,-.041001,
.023747,-.045427,
.019926,-.049248,
.015499,-.052348,
.010602,-.054632,
.0075,-.05558,
0.0*
4,1,20,-.031,.0075,
-.031,.0255,
-.030529,.030883,
-.02913,.036103,
-.026847,.041001,
-.023747,.045427,
-.019926,.049248,
-.015499,.052348,
-.010602,.054632,
-.0075,.05558,
-.0075,.0483,
-.011345,.046651,
-.014846,.044359,
-.017895,.041494,
-.0204,.038143,
-.022286,.034408,
-.023494,.030402,
-.023988,.026248,
-.024,.0255,
-.024,.0075,
-.031,.0075,
0.0*
4,1,20,.024,.0075,
.024,.0255,
.023635,.029668,
.022552,.033709,
.020784,.037501,
.018384,.040929,
.015426,.043887,
.011999,.046287,
.008207,.048055,
.0075,.0483,
.0075,.05558,
.012609,.05382,
.017336,.0512,
.021535,.047799,
.02508,.043721,
.027863,.039089,
.029799,.034044,
.03083,.028739,
.031,.0255,
.031,.0075,
.024,.0075,
0.0*
%
%ADD26MACRO26*%
%AMMACRO23*
4,1,15,.02364,.01304,
.025545,.008737,
.026674,.004168,
.026993,-.000527,
.026491,-.005206,
.025185,-.009727,
.02364,-.01304,
.02875,-.01815,
.031465,-.012882,
.033224,-.007222,
.033973,-.001343,
.03369,.004576,
.032384,.010357,
.030093,.015823,
.02875,.01815,
.02364,.01304,
0.0*
4,1,15,.01304,-.02364,
.008737,-.025545,
.004168,-.026674,
-.000527,-.026993,
-.005206,-.026491,
-.009727,-.025185,
-.01304,-.02364,
-.01815,-.02875,
-.012882,-.031465,
-.007222,-.033224,
-.001343,-.033973,
.004576,-.03369,
.010357,-.032384,
.015823,-.030093,
.01815,-.02875,
.01304,-.02364,
0.0*
4,1,15,-.02364,-.01304,
-.025545,-.008737,
-.026674,-.004168,
-.026993,.000527,
-.026491,.005206,
-.025185,.009727,
-.02364,.01304,
-.02875,.01815,
-.031465,.012882,
-.033224,.007222,
-.033973,.001343,
-.03369,-.004576,
-.032384,-.010357,
-.030093,-.015823,
-.02875,-.01815,
-.02364,-.01304,
0.0*
4,1,15,-.01304,.02364,
-.008737,.025545,
-.004168,.026674,
.000527,.026993,
.005206,.026491,
.009727,.025185,
.01304,.02364,
.01815,.02875,
.012882,.031465,
.007222,.033224,
.001343,.033973,
-.004576,.03369,
-.010357,.032384,
-.015823,.030093,
-.01815,.02875,
-.01304,.02364,
0.0*
%
%ADD23MACRO23*%
%AMMACRO31*
4,1,15,.03682,.01914,
.039584,.012455,
.041146,.005393,
.041457,-.001834,
.040509,-.009005,
.03833,-.015903,
.03682,-.01914,
.04197,-.0243,
.045552,-.016643,
.04775,-.00848,
.048497,-.000059,
.047771,.008363,
.045593,.016531,
.042029,.024197,
.04197,.0243,
.03682,.01914,
0.0*
4,1,15,.01914,-.03682,
.012455,-.039584,
.005393,-.041146,
-.001834,-.041457,
-.009005,-.040509,
-.015903,-.03833,
-.01914,-.03682,
-.0243,-.04197,
-.016643,-.045552,
-.00848,-.04775,
-.000059,-.048497,
.008363,-.047771,
.016531,-.045593,
.024197,-.042029,
.0243,-.04197,
.01914,-.03682,
0.0*
4,1,15,-.03682,-.01914,
-.039584,-.012455,
-.041146,-.005393,
-.041457,.001834,
-.040509,.009005,
-.03833,.015903,
-.03682,.01914,
-.04197,.0243,
-.045552,.016643,
-.04775,.00848,
-.048497,.000059,
-.047771,-.008363,
-.045593,-.016531,
-.042029,-.024197,
-.04197,-.0243,
-.03682,-.01914,
0.0*
4,1,15,-.01914,.03682,
-.012455,.039584,
-.005393,.041146,
.001834,.041457,
.009005,.040509,
.015903,.03833,
.01914,.03682,
.0243,.04197,
.016643,.045552,
.00848,.04775,
.000059,.048497,
-.008363,.047771,
-.016531,.045593,
-.024197,.042029,
-.0243,.04197,
-.01914,.03682,
0.0*
%
%ADD31MACRO31*%
%AMMACRO14*
4,1,36,0.0,.01,
-.001736,.009848,
-.00342,.009397,
-.005,.00866,
-.006428,.00766,
-.00766,.006428,
-.00866,.005,
-.009397,.00342,
-.009848,.001736,
-.01,0.0,
-.009848,-.001736,
-.009397,-.00342,
-.00866,-.005,
-.00766,-.006428,
-.006428,-.00766,
-.005,-.00866,
-.00342,-.009397,
-.001736,-.009848,
0.0,-.01,
.001736,-.009848,
.00342,-.009397,
.005,-.00866,
.006428,-.00766,
.00766,-.006428,
.00866,-.005,
.009397,-.00342,
.009848,-.001736,
.01,0.0,
.009848,.001736,
.009397,.00342,
.00866,.005,
.00766,.006428,
.006428,.00766,
.005,.00866,
.00342,.009397,
.001736,.009848,
0.0,.01,
180.*
%
%ADD14MACRO14*%
%ADD10C,.125*%
%ADD15C,.155*%
%ADD18C,.149*%
%AMMACRO34*
4,1,36,.0025,0.0,
.002462,.000434,
.002349,.000855,
.002165,.00125,
.001915,.001607,
.001607,.001915,
.00125,.002165,
.000855,.002349,
.000434,.002462,
0.0,.0025,
-.000434,.002462,
-.000855,.002349,
-.00125,.002165,
-.001607,.001915,
-.001915,.001607,
-.002165,.00125,
-.002349,.000855,
-.002462,.000434,
-.0025,0.0,
-.002462,-.000434,
-.002349,-.000855,
-.002165,-.00125,
-.001915,-.001607,
-.001607,-.001915,
-.00125,-.002165,
-.000855,-.002349,
-.000434,-.002462,
0.0,-.0025,
.000434,-.002462,
.000855,-.002349,
.00125,-.002165,
.001607,-.001915,
.001915,-.001607,
.002165,-.00125,
.002349,-.000855,
.002462,-.000434,
.0025,0.0,
90.*
%
%ADD34MACRO34*%
%AMMACRO39*
4,1,36,.003,0.0,
.002954,.000521,
.002819,.001026,
.002598,.0015,
.002298,.001928,
.001928,.002298,
.0015,.002598,
.001026,.002819,
.000521,.002954,
0.0,.003,
-.000521,.002954,
-.001026,.002819,
-.0015,.002598,
-.001928,.002298,
-.002298,.001928,
-.002598,.0015,
-.002819,.001026,
-.002954,.000521,
-.003,0.0,
-.002954,-.000521,
-.002819,-.001026,
-.002598,-.0015,
-.002298,-.001928,
-.001928,-.002298,
-.0015,-.002598,
-.001026,-.002819,
-.000521,-.002954,
0.0,-.003,
.000521,-.002954,
.001026,-.002819,
.0015,-.002598,
.001928,-.002298,
.002298,-.001928,
.002598,-.0015,
.002819,-.001026,
.002954,-.000521,
.003,0.0,
90.*
%
%ADD39MACRO39*%
%AMMACRO36*
4,1,36,-.0025,0.0,
-.002462,.000434,
-.002349,.000855,
-.002165,.00125,
-.001915,.001607,
-.001607,.001915,
-.00125,.002165,
-.000855,.002349,
-.000434,.002462,
0.0,.0025,
.000434,.002462,
.000855,.002349,
.00125,.002165,
.001607,.001915,
.001915,.001607,
.002165,.00125,
.002349,.000855,
.002462,.000434,
.0025,0.0,
.002462,-.000434,
.002349,-.000855,
.002165,-.00125,
.001915,-.001607,
.001607,-.001915,
.00125,-.002165,
.000855,-.002349,
.000434,-.002462,
0.0,-.0025,
-.000434,-.002462,
-.000855,-.002349,
-.00125,-.002165,
-.001607,-.001915,
-.001915,-.001607,
-.002165,-.00125,
-.002349,-.000855,
-.002462,-.000434,
-.0025,0.0,
90.*
%
%ADD36MACRO36*%
%AMMACRO11*
4,1,36,.0025,0.0,
.002462,.000434,
.002349,.000855,
.002165,.00125,
.001915,.001607,
.001607,.001915,
.00125,.002165,
.000855,.002349,
.000434,.002462,
0.0,.0025,
-.000434,.002462,
-.000855,.002349,
-.00125,.002165,
-.001607,.001915,
-.001915,.001607,
-.002165,.00125,
-.002349,.000855,
-.002462,.000434,
-.0025,0.0,
-.002462,-.000434,
-.002349,-.000855,
-.002165,-.00125,
-.001915,-.001607,
-.001607,-.001915,
-.00125,-.002165,
-.000855,-.002349,
-.000434,-.002462,
0.0,-.0025,
.000434,-.002462,
.000855,-.002349,
.00125,-.002165,
.001607,-.001915,
.001915,-.001607,
.002165,-.00125,
.002349,-.000855,
.002462,-.000434,
.0025,0.0,
0.0*
%
%ADD11MACRO11*%
%ADD17C,.188*%
%AMMACRO32*
4,1,15,.03682,.01914,
.039584,.012455,
.041146,.005393,
.041457,-.001834,
.040509,-.009005,
.03833,-.015903,
.03682,-.01914,
.04197,-.0243,
.045552,-.016643,
.04775,-.00848,
.048497,-.000059,
.047771,.008363,
.045593,.016531,
.042029,.024197,
.04197,.0243,
.03682,.01914,
180.*
4,1,15,.01914,-.03682,
.012455,-.039584,
.005393,-.041146,
-.001834,-.041457,
-.009005,-.040509,
-.015903,-.03833,
-.01914,-.03682,
-.0243,-.04197,
-.016643,-.045552,
-.00848,-.04775,
-.000059,-.048497,
.008363,-.047771,
.016531,-.045593,
.024197,-.042029,
.0243,-.04197,
.01914,-.03682,
180.*
4,1,15,-.03682,-.01914,
-.039584,-.012455,
-.041146,-.005393,
-.041457,.001834,
-.040509,.009005,
-.03833,.015903,
-.03682,.01914,
-.04197,.0243,
-.045552,.016643,
-.04775,.00848,
-.048497,.000059,
-.047771,-.008363,
-.045593,-.016531,
-.042029,-.024197,
-.04197,-.0243,
-.03682,-.01914,
180.*
4,1,15,-.01914,.03682,
-.012455,.039584,
-.005393,.041146,
.001834,.041457,
.009005,.040509,
.015903,.03833,
.01914,.03682,
.0243,.04197,
.016643,.045552,
.00848,.04775,
.000059,.048497,
-.008363,.047771,
-.016531,.045593,
-.024197,.042029,
-.0243,.04197,
-.01914,.03682,
180.*
%
%ADD32MACRO32*%
%AMMACRO29*
4,1,20,-.0075,-.0348,
-.0075,-.04208,
-.012609,-.04032,
-.017336,-.0377,
-.021535,-.034299,
-.02508,-.030221,
-.027863,-.025589,
-.029799,-.020544,
-.03083,-.015239,
-.031,-.012,
-.031,-.0075,
-.024,-.0075,
-.024,-.012,
-.023635,-.016168,
-.022552,-.020209,
-.020784,-.024001,
-.018384,-.027429,
-.015426,-.030387,
-.011999,-.032787,
-.008207,-.034555,
-.0075,-.0348,
0.0*
4,1,20,.0075,-.04208,
.0075,-.0348,
.011345,-.033151,
.014846,-.030859,
.017895,-.027994,
.0204,-.024643,
.022286,-.020908,
.023494,-.016902,
.023988,-.012748,
.024,-.012,
.024,-.0075,
.031,-.0075,
.031,-.012,
.030529,-.017383,
.02913,-.022603,
.026847,-.027501,
.023747,-.031927,
.019926,-.035748,
.015499,-.038848,
.010602,-.041132,
.0075,-.04208,
0.0*
4,1,20,-.0075,.04208,
-.0075,.0348,
-.011345,.033151,
-.014846,.030859,
-.017895,.027994,
-.0204,.024643,
-.022286,.020908,
-.023494,.016902,
-.023988,.012748,
-.024,.012,
-.024,.0075,
-.031,.0075,
-.031,.012,
-.030529,.017383,
-.02913,.022603,
-.026847,.027501,
-.023747,.031927,
-.019926,.035748,
-.015499,.038848,
-.010602,.041132,
-.0075,.04208,
0.0*
4,1,20,.0075,.0348,
.0075,.04208,
.012609,.04032,
.017336,.0377,
.021535,.034299,
.02508,.030221,
.027863,.025589,
.029799,.020544,
.03083,.015239,
.031,.012,
.031,.0075,
.024,.0075,
.024,.012,
.023635,.016168,
.022552,.020209,
.020784,.024001,
.018384,.027429,
.015426,.030387,
.011999,.032787,
.008207,.034555,
.0075,.0348,
0.0*
%
%ADD29MACRO29*%
%ADD40C,.006*%
%ADD45C,.07306*%
%ADD42C,.08607*%
%ADD43C,.08609*%
%ADD44C,.16506*%
%ADD41C,.19806*%
G75*
%LPD*%
G75*
G36*
G01X-247901Y-428634D02*
X2091018D01*
Y1008173D01*
X-247901D01*
Y-428634D01*
G37*
%LPC*%
G75*
G36*
G01X113583Y337169D02*
G02X119453Y331299I0J-5870D01*
G01Y322835D01*
G03X129331Y312957I9878J0D01*
G01X142520D01*
G02X148390Y307087I0J-5870D01*
G01Y283263D01*
G03X151106Y276461I9878J1D01*
G02X152720Y272419I-4257J-4043D01*
G01Y190480D01*
X152729Y190471D01*
Y190160D01*
X152720Y190151D01*
Y7869D01*
G02X152598Y6682I-5870J4D01*
G01Y6680D01*
G02X146855Y2043I-5743J1238D01*
G01X7879D01*
G02X2005Y7917I0J5874D01*
G01Y272460D01*
G02X2006Y272576I5875J7D01*
G01Y272578D01*
G02X3618Y276461I5869J-160D01*
G03X6333Y283055I-7161J6804D01*
G03X6336Y283307I-9871J244D01*
G01Y307130D01*
G02X6337Y307244I5874J5D01*
G01Y307246D01*
G02X12205Y312957I5868J-159D01*
G01X42716D01*
G03X52592Y322627I0J9878D01*
G03X52595Y322878I-9871J243D01*
G01Y331342D01*
G02X52596Y331456I5874J5D01*
G01Y331458D01*
G02X58464Y337169I5868J-159D01*
G01X113583D01*
G37*
G36*
G01X333217Y2006D02*
G02X333153I-32J6017D01*
G01X333151D01*
G02X327200Y7957I1J5952D01*
G01Y7959D01*
G02Y8023I6017J32D01*
G01Y188030D01*
X327196Y188034D01*
Y192516D01*
X327200Y192520D01*
Y272669D01*
G02X327400Y272869I200J0D01*
G01X389921D01*
G02X390121Y272669I0J-200D01*
G01Y7907D01*
G02X384220Y2006I-5901J0D01*
G01X333217D01*
G37*
G36*
G01X384220Y684220D02*
G02X390121Y678319I0J-5901D01*
G01Y275069D01*
G02X389921Y274869I-200J0D01*
G01X327400D01*
G02X327200Y275069I0J200D01*
G01Y678559D01*
Y678567D01*
G02X327283Y679348I5869J-229D01*
G01Y679352D01*
G02X333166Y684220I5883J-1121D01*
G01X384220D01*
G37*
%LPD*%
G75*
G36*
G01X91881Y72165D02*
G02X97883I3001J0D01*
G02X97321Y70417I-3001J0D01*
G03X97284Y70301I163J-116D01*
G01Y66153D01*
G03X97321Y66037I200J0D01*
G02X97882Y64291I-2438J-1746D01*
G02X91882I-3000J0D01*
G02X92443Y66037I2999J0D01*
G03X92480Y66153I-163J116D01*
G01Y70301D01*
G03X92443Y70417I-200J0D01*
G02X91881Y72165I2439J1748D01*
G37*
G36*
G01X18076Y279449D02*
Y282093D01*
G03X16771Y285783I-5872J-1D01*
G02X35197I9213J7445D01*
G03X33892Y282094I4566J-3691D01*
G01Y279449D01*
G02X18076I-7908J0D01*
G37*
G36*
G01X129866Y84271D02*
Y81984D01*
G02X129763Y81882I-103J1D01*
G01X127044D01*
X127043D01*
G02X126940Y81984I-1J102D01*
G01Y84271D01*
G02X127043Y84374I103J0D01*
G01X129763D01*
G02X129866Y84271I0J-103D01*
G37*
G36*
G01X121992D02*
Y81984D01*
G02X121889Y81882I-103J1D01*
G01X119170D01*
X119169D01*
G02X119066Y81984I-1J102D01*
G01Y84271D01*
G02X119169Y84374I103J0D01*
G01X121889D01*
G02X121992Y84271I0J-103D01*
G37*
G36*
G01X123838Y99068D02*
Y94443D01*
G02X123735Y94340I-103J0D01*
G01X121760D01*
G02X121658Y94443I1J103D01*
G01Y99068D01*
G02X121760Y99170I102J0D01*
G01X123734D01*
X123735D01*
G02X123838Y99068I1J-102D01*
G37*
G36*
G01X127156Y92978D02*
Y88688D01*
G02X127054Y88586I-102J0D01*
G01X125186D01*
X125185D01*
G02X125082Y88688I-1J102D01*
G01Y92978D01*
G02X125185Y93080I103J-1D01*
G01X127054D01*
G02X127156Y92978I0J-102D01*
G37*
G36*
G01X127184Y99068D02*
Y94443D01*
G02X127081Y94340I-103J0D01*
G01X125106D01*
G02X125004Y94443I1J103D01*
G01Y99068D01*
G02X125106Y99170I102J0D01*
G01X127080D01*
X127081D01*
G02X127184Y99068I1J-102D01*
G37*
G36*
G01X105750Y277395D02*
Y272204D01*
Y272203D01*
G02X105648Y272100I-102J-1D01*
G01X101875D01*
G02X101772Y272203I0J103D01*
G01Y277395D01*
G02X101875Y277498I103J0D01*
G01X105648D01*
G02X105750Y277395I-1J-103D01*
G37*
G36*
G01X123810Y92978D02*
Y88688D01*
G02X123708Y88586I-102J0D01*
G01X121840D01*
X121839D01*
G02X121736Y88688I-1J102D01*
G01Y92978D01*
G02X121839Y93080I103J-1D01*
G01X123708D01*
G02X123810Y92978I0J-102D01*
G37*
G36*
G01X144130Y43425D02*
G02X128312I-7909J0D01*
G01Y46070D01*
G03X127008Y49759I-5872J-1D01*
G02X145434I9213J7445D01*
G03X144130Y46070I4567J-3689D01*
G01Y43425D01*
G37*
G36*
G01X343330Y609628D02*
X347650D01*
G02X347952Y609326I0J-302D01*
G01Y606916D01*
G02X347650Y606614I-302J0D01*
G01X343330D01*
G02X343028Y606916I0J302D01*
G01Y609326D01*
G02X343330Y609628I302J0D01*
G37*
G36*
G01X347670Y432872D02*
X343350D01*
G02X343048Y433174I0J302D01*
G01Y435584D01*
G02X343350Y435886I302J0D01*
G01X347670D01*
G02X347972Y435584I0J-302D01*
G01Y433174D01*
G02X347670Y432872I-302J0D01*
G37*
G36*
G01X377170Y329058D02*
X372850D01*
G02X372548Y329360I0J302D01*
G01Y331770D01*
G02X372850Y332072I302J0D01*
G01X377170D01*
G02X377472Y331770I0J-302D01*
G01Y329360D01*
G02X377170Y329058I-302J0D01*
G37*
G36*
G01X372830Y609628D02*
X377150D01*
G02X377452Y609326I0J-302D01*
G01Y606916D01*
G02X377150Y606614I-302J0D01*
G01X372830D01*
G02X372528Y606916I0J302D01*
G01Y609326D01*
G02X372830Y609628I302J0D01*
G37*
G54D45*
X370000Y316336D03*
X380000D03*
Y341336D03*
X370000D03*
X350500Y445150D03*
Y622350D03*
X340500D03*
Y597350D03*
X350500D03*
X380000Y622350D03*
X370000D03*
Y597350D03*
X380000D03*
X340500Y420150D03*
Y445150D03*
X350500Y420150D03*
G54D42*
X64174Y294685D03*
G54D43*
X107874D03*
G54D44*
X14000Y255500D03*
X60989Y131906D03*
X134016Y147928D03*
X372440Y19685D03*
Y666535D03*
G54D41*
X24016Y58661D03*
X129134Y247543D03*
G54D13*
X10315Y13000D03*
X8000Y103500D03*
Y114500D03*
X11500Y196000D03*
Y188000D03*
Y204000D03*
X19500Y209500D03*
Y217500D03*
Y225500D03*
Y233500D03*
Y241500D03*
X59500Y55000D03*
X52000Y81000D03*
X59500Y95000D03*
X42400Y86500D03*
X41500Y103500D03*
X41038Y112537D03*
X55925Y204000D03*
X63600Y34192D03*
X72555Y46921D03*
X64500Y63500D03*
X66925Y70000D03*
X70075Y64500D03*
X68720Y54000D03*
X81729Y77772D03*
X73000Y91000D03*
Y87000D03*
X65000Y73500D03*
X73000Y95000D03*
X78500Y110000D03*
Y112500D03*
X75425Y102000D03*
X59500Y117960D03*
X76000Y123000D03*
Y126500D03*
X78340Y136000D03*
X67000Y177500D03*
X66500Y181500D03*
Y185500D03*
Y189500D03*
Y193500D03*
X68500Y231500D03*
X76500Y239500D03*
Y235500D03*
Y231500D03*
X64000Y258000D03*
X66500D03*
X65925Y247000D03*
X72500Y258000D03*
X70000D03*
X75394Y288205D03*
X68308D03*
X84500Y76500D03*
X81000Y91000D03*
Y95000D03*
X83500Y133000D03*
Y129500D03*
X88500Y123500D03*
X92500Y126000D03*
X80310Y138735D03*
X96654Y288205D03*
X89567D03*
X106954Y21716D03*
X111965Y11716D03*
X109812Y16716D03*
X122130Y30217D03*
X107318Y63176D03*
X106970Y65827D03*
Y68327D03*
X112000Y147000D03*
Y150500D03*
X115000Y147000D03*
Y150500D03*
X132000Y10500D03*
X139500D03*
X127500Y6716D03*
X137000Y84500D03*
Y88000D03*
Y92000D03*
X134500Y136500D03*
Y133000D03*
Y129500D03*
Y126000D03*
Y122500D03*
Y119000D03*
X148500Y76000D03*
Y84000D03*
Y92000D03*
Y108000D03*
Y100000D03*
G54D12*
X10315Y20079D03*
X33937D03*
X20315D03*
X43937D03*
G54D33*
X350500Y420150D03*
X340500D03*
X350500Y445150D03*
X340500D03*
Y597350D03*
X350500D03*
X340500Y622350D03*
X350500D03*
X380000Y316336D03*
X370000D03*
X380000Y341336D03*
X370000D03*
Y597350D03*
X380000D03*
X370000Y622350D03*
X380000D03*
G54D16*
X13984Y279449D03*
X78937Y270653D03*
X80119Y288205D03*
X86024Y270653D03*
X93111D03*
X84843Y288205D03*
X101378D03*
X106103D03*
X124221Y43425D03*
G54D19*
X34469Y270964D03*
X144706Y34940D03*
G54D20*
X25984Y267449D03*
X136221Y31425D03*
X350539Y607802D03*
X351845Y614080D03*
X349330Y614095D03*
X340010Y607802D03*
X369510D03*
X378830Y614095D03*
X381345Y614080D03*
X380039Y607802D03*
G54D21*
X17499Y270964D03*
X127736Y34940D03*
G54D24*
X64174Y294685D03*
X107874D03*
G54D35*
X341684Y431703D03*
X339169Y431688D03*
X349698D03*
X352213Y431703D03*
X344419Y428405D03*
X346934Y428420D03*
X352199Y428435D03*
X349684Y428420D03*
X371184Y327889D03*
X368669Y327874D03*
X379198D03*
X373919Y324591D03*
X376434Y324606D03*
X379184D03*
X381713Y327889D03*
X381699Y324621D03*
G54D38*
X370195Y83000D03*
X380195D03*
G54D27*
X101969Y52480D03*
Y68228D03*
Y60354D03*
X94882Y64291D03*
Y72165D03*
Y82008D03*
X101969Y83976D03*
Y76102D03*
G54D37*
X370195Y93000D03*
X380195D03*
Y247618D03*
X370195D03*
G54D22*
X57480Y26299D03*
X77480D03*
G54D30*
X339937Y104912D03*
X349937D03*
X352033Y234525D03*
X342033D03*
G54D25*
X61516Y326772D03*
Y314961D03*
X110532Y326772D03*
Y314961D03*
G54D28*
X94882Y54449D03*
G54D26*
X87756Y47244D03*
X109095Y89370D03*
G54D23*
X67480Y26299D03*
G54D31*
X344937Y91728D03*
G54D14*
X13553Y48198D03*
Y69124D03*
X9218Y58661D03*
X34479Y48198D03*
X24016Y43863D03*
X34479Y69124D03*
X24016Y73459D03*
X38814Y58661D03*
X118671Y237080D03*
Y258006D03*
X114336Y247543D03*
X139597Y237080D03*
X129134Y232745D03*
Y262341D03*
X139597Y258006D03*
X143932Y247543D03*
G54D10*
X-58189Y19685D03*
Y666535D03*
X372440Y19685D03*
Y666535D03*
G54D15*
X14000Y255500D03*
X60989Y131906D03*
X134016Y147928D03*
G54D18*
X25984Y279449D03*
X136221Y43425D03*
G54D34*
X350990Y434698D03*
X341670Y428405D03*
X339155Y428420D03*
X340461Y434698D03*
X371170Y324591D03*
X368655Y324606D03*
X369961Y330884D03*
X380490D03*
G54D11*
X5192Y3841D03*
X3004Y90860D03*
Y106468D03*
X8000Y99500D03*
Y110500D03*
X16000Y98441D03*
Y109441D03*
X3004Y126468D03*
Y146468D03*
Y166468D03*
X11500Y200000D03*
Y192000D03*
Y184000D03*
X3004Y186468D03*
Y206468D03*
Y226468D03*
Y246468D03*
X7348Y302588D03*
X7337Y292952D03*
X27028Y3019D03*
X33000Y186000D03*
X19500Y221500D03*
Y213500D03*
Y229500D03*
Y237500D03*
Y245500D03*
X35701Y311937D03*
X16801Y311946D03*
X46184Y3014D03*
X59586Y40000D03*
X48941Y89500D03*
X54059Y102500D03*
X41000Y213532D03*
X59075Y204000D03*
X56500Y261000D03*
X57800Y263900D03*
X37984Y279449D03*
X51404Y316245D03*
X53595Y331234D03*
X60867Y3014D03*
X81000Y8000D03*
X77382Y58000D03*
X62500Y55000D03*
X77453Y77500D03*
X66000Y118000D03*
X70000Y138500D03*
X70500Y177500D03*
X64075Y200000D03*
X76500Y227500D03*
X76400Y258000D03*
X69075Y247000D03*
X75700Y263900D03*
X64764Y288205D03*
X71851D03*
X68968Y336145D03*
X80697Y3016D03*
X98502D03*
X99500Y9000D03*
X91000Y18500D03*
X99000Y65500D03*
X84500Y95000D03*
X81500Y126500D03*
X94500Y129000D03*
X93111Y288205D03*
X100197Y270653D03*
X83076Y336146D03*
X118500Y6716D03*
X117186Y3014D03*
X113181Y31701D03*
X118000Y116500D03*
X120500Y136500D03*
Y129500D03*
Y133000D03*
Y126000D03*
X107284Y270653D03*
X118455Y323862D03*
X116870Y334863D03*
X103076Y336146D03*
X136936Y3035D03*
X128385Y80000D03*
X133500Y160000D03*
X132500Y185000D03*
X129715Y311960D03*
X150330Y4601D03*
X151688Y13776D03*
X148221Y43425D03*
X151706Y72716D03*
X151683Y90942D03*
X148500Y88000D03*
Y80000D03*
X151684Y112798D03*
X148500Y96000D03*
Y112000D03*
Y104000D03*
X151684Y132682D03*
X148500Y136500D03*
Y133000D03*
Y129500D03*
Y126000D03*
Y122500D03*
Y119000D03*
Y115500D03*
X151683Y151482D03*
X151705Y172913D03*
X151663Y192669D03*
X151662Y212615D03*
X151704Y232645D03*
X151705Y252655D03*
X144561Y311483D03*
G54D36*
X338801Y614065D03*
X341316Y614080D03*
X338787Y610797D03*
X341302Y610812D03*
X344066Y614080D03*
X346581Y614095D03*
X351831Y610812D03*
X349316Y610797D03*
X378816D03*
X370802Y610812D03*
X368287Y610797D03*
X376081Y614095D03*
X373566Y614080D03*
X368301Y614065D03*
X370816Y614080D03*
X381331Y610812D03*
G54D39*
X380195Y257618D03*
X370195D03*
G54D17*
X24016Y58661D03*
X129134Y247543D03*
G54D29*
X87756Y89370D03*
X109095Y47244D03*
G54D32*
X347033Y247709D03*
%LPC*%
G75*
G54D40*
G01X-117168Y-317735D02*
Y-322735D01*
G01X-118625Y-317735D02*
X-115711D01*
G01X-110801Y-322735D02*
X-113335D01*
Y-317735D01*
X-110801D01*
G01X-111815Y-320152D02*
X-113335D01*
G01X-108235Y-317735D02*
Y-322735D01*
X-105701D01*
G01X-101868Y-322902D02*
X-101995Y-322818D01*
Y-322652D01*
X-101868Y-322568D01*
X-101741Y-322652D01*
Y-322818D01*
X-101868Y-322902D01*
G01Y-320652D02*
X-101995Y-320568D01*
Y-320402D01*
X-101868Y-320318D01*
X-101741Y-320402D01*
Y-320568D01*
X-101868Y-320652D01*
G01X-97085Y-324402D02*
X-97718Y-323568D01*
X-98035Y-322735D01*
Y-319402D01*
X-97718Y-318568D01*
X-97085Y-317735D01*
G01X-91668D02*
X-92175Y-317902D01*
X-92555Y-318318D01*
X-92808Y-318818D01*
X-92998Y-319485D01*
X-93061Y-320235D01*
X-92998Y-320985D01*
X-92808Y-321652D01*
X-92555Y-322152D01*
X-92175Y-322568D01*
X-91668Y-322735D01*
X-91161Y-322568D01*
X-90781Y-322152D01*
X-90528Y-321652D01*
X-90338Y-320985D01*
X-90275Y-320235D01*
X-90338Y-319485D01*
X-90528Y-318818D01*
X-90781Y-318318D01*
X-91161Y-317902D01*
X-91668Y-317735D01*
G01X-87961Y-321735D02*
X-87581Y-322318D01*
X-87075Y-322652D01*
X-86505Y-322735D01*
X-85998Y-322652D01*
X-85491Y-322235D01*
X-85175Y-321735D01*
X-85111Y-321235D01*
X-85238Y-320652D01*
X-85681Y-320235D01*
X-86125Y-320068D01*
X-86695D01*
G01X-86125D02*
X-85745Y-319818D01*
X-85428Y-319402D01*
X-85301Y-318902D01*
X-85428Y-318402D01*
X-85745Y-317985D01*
X-86315Y-317735D01*
X-86885Y-317818D01*
X-87455Y-318152D01*
G01X-81151Y-324402D02*
X-80518Y-323568D01*
X-80201Y-322735D01*
Y-319402D01*
X-80518Y-318568D01*
X-81151Y-317735D01*
G01X-77761Y-321735D02*
X-77381Y-322318D01*
X-76875Y-322652D01*
X-76305Y-322735D01*
X-75798Y-322652D01*
X-75291Y-322235D01*
X-74975Y-321735D01*
X-74911Y-321235D01*
X-75038Y-320652D01*
X-75481Y-320235D01*
X-75925Y-320068D01*
X-76495D01*
G01X-75925D02*
X-75545Y-319818D01*
X-75228Y-319402D01*
X-75101Y-318902D01*
X-75228Y-318402D01*
X-75545Y-317985D01*
X-76115Y-317735D01*
X-76685Y-317818D01*
X-77255Y-318152D01*
G01X-72471Y-318568D02*
X-72091Y-318068D01*
X-71648Y-317818D01*
X-71141Y-317735D01*
X-70508Y-317902D01*
X-70065Y-318318D01*
X-69938Y-318818D01*
X-70001Y-319318D01*
X-70255Y-319735D01*
X-71521Y-320568D01*
X-72091Y-321152D01*
X-72471Y-321985D01*
X-72598Y-322735D01*
X-69938D01*
G01X-66295D02*
X-66168Y-321652D01*
X-65978Y-320735D01*
X-65725Y-319902D01*
X-65408Y-318985D01*
X-64901Y-317735D01*
X-67435D01*
G01X-61891Y-321068D02*
X-60245D01*
G01X-57171Y-318568D02*
X-56791Y-318068D01*
X-56348Y-317818D01*
X-55841Y-317735D01*
X-55208Y-317902D01*
X-54765Y-318318D01*
X-54638Y-318818D01*
X-54701Y-319318D01*
X-54955Y-319735D01*
X-56221Y-320568D01*
X-56791Y-321152D01*
X-57171Y-321985D01*
X-57298Y-322735D01*
X-54638D01*
G01X-52261Y-321735D02*
X-51881Y-322318D01*
X-51375Y-322652D01*
X-50805Y-322735D01*
X-50298Y-322652D01*
X-49791Y-322235D01*
X-49475Y-321735D01*
X-49411Y-321235D01*
X-49538Y-320652D01*
X-49981Y-320235D01*
X-50425Y-320068D01*
X-50995D01*
G01X-50425D02*
X-50045Y-319818D01*
X-49728Y-319402D01*
X-49601Y-318902D01*
X-49728Y-318402D01*
X-50045Y-317985D01*
X-50615Y-317735D01*
X-51185Y-317818D01*
X-51755Y-318152D01*
G01X-45008Y-322735D02*
Y-317735D01*
X-47351Y-321318D01*
X-44185D01*
G01X-42061Y-321985D02*
X-41681Y-322402D01*
X-41238Y-322652D01*
X-40668Y-322735D01*
X-40098Y-322568D01*
X-39655Y-322235D01*
X-39338Y-321652D01*
X-39275Y-320985D01*
X-39401Y-320318D01*
X-39718Y-319902D01*
X-40161Y-319568D01*
X-40605Y-319485D01*
X-41048Y-319568D01*
X-41618Y-319902D01*
X-41428Y-317735D01*
X-39718D01*
G01X-31671Y-322735D02*
Y-317735D01*
X-29265D01*
G01X-30151Y-320152D02*
X-31671D01*
G01X-26951Y-322735D02*
X-25368Y-317735D01*
X-23785Y-322735D01*
G01X-24355Y-320985D02*
X-26381D01*
G01X-21598Y-322735D02*
X-18938Y-317735D01*
G01X-21598D02*
X-18938Y-322735D01*
G01X-15168Y-322902D02*
X-15295Y-322818D01*
Y-322652D01*
X-15168Y-322568D01*
X-15041Y-322652D01*
Y-322818D01*
X-15168Y-322902D01*
G01Y-320652D02*
X-15295Y-320568D01*
Y-320402D01*
X-15168Y-320318D01*
X-15041Y-320402D01*
Y-320568D01*
X-15168Y-320652D01*
G01X-10385Y-324402D02*
X-11018Y-323568D01*
X-11335Y-322735D01*
Y-319402D01*
X-11018Y-318568D01*
X-10385Y-317735D01*
G01X-4968D02*
X-5475Y-317902D01*
X-5855Y-318318D01*
X-6108Y-318818D01*
X-6298Y-319485D01*
X-6361Y-320235D01*
X-6298Y-320985D01*
X-6108Y-321652D01*
X-5855Y-322152D01*
X-5475Y-322568D01*
X-4968Y-322735D01*
X-4461Y-322568D01*
X-4081Y-322152D01*
X-3828Y-321652D01*
X-3638Y-320985D01*
X-3575Y-320235D01*
X-3638Y-319485D01*
X-3828Y-318818D01*
X-4081Y-318318D01*
X-4461Y-317902D01*
X-4968Y-317735D01*
G01X-1261Y-321735D02*
X-881Y-322318D01*
X-375Y-322652D01*
X195Y-322735D01*
X702Y-322652D01*
X1209Y-322235D01*
X1525Y-321735D01*
X1589Y-321235D01*
X1462Y-320652D01*
X1019Y-320235D01*
X575Y-320068D01*
X5D01*
G01X575D02*
X955Y-319818D01*
X1272Y-319402D01*
X1399Y-318902D01*
X1272Y-318402D01*
X955Y-317985D01*
X385Y-317735D01*
X-185Y-317818D01*
X-755Y-318152D01*
G01X5549Y-324402D02*
X6182Y-323568D01*
X6499Y-322735D01*
Y-319402D01*
X6182Y-318568D01*
X5549Y-317735D01*
G01X8939Y-321735D02*
X9319Y-322318D01*
X9825Y-322652D01*
X10395Y-322735D01*
X10902Y-322652D01*
X11409Y-322235D01*
X11725Y-321735D01*
X11789Y-321235D01*
X11662Y-320652D01*
X11219Y-320235D01*
X10775Y-320068D01*
X10205D01*
G01X10775D02*
X11155Y-319818D01*
X11472Y-319402D01*
X11599Y-318902D01*
X11472Y-318402D01*
X11155Y-317985D01*
X10585Y-317735D01*
X10015Y-317818D01*
X9445Y-318152D01*
G01X14355Y-322152D02*
X14799Y-322568D01*
X15305Y-322735D01*
X15812Y-322568D01*
X16255Y-322068D01*
X16572Y-321318D01*
X16699Y-320568D01*
Y-319652D01*
X16572Y-318902D01*
X16255Y-318235D01*
X15875Y-317902D01*
X15432Y-317735D01*
X14925Y-317902D01*
X14545Y-318235D01*
X14292Y-318735D01*
X14165Y-319402D01*
X14292Y-319985D01*
X14609Y-320568D01*
X14989Y-320902D01*
X15432Y-320985D01*
X15939Y-320818D01*
X16319Y-320402D01*
X16699Y-319652D01*
G01X20405Y-322735D02*
X20532Y-321652D01*
X20722Y-320735D01*
X20975Y-319902D01*
X21292Y-318985D01*
X21799Y-317735D01*
X19265D01*
G01X24809Y-321068D02*
X26455D01*
G01X29339Y-321735D02*
X29719Y-322318D01*
X30225Y-322652D01*
X30795Y-322735D01*
X31302Y-322652D01*
X31809Y-322235D01*
X32125Y-321735D01*
X32189Y-321235D01*
X32062Y-320652D01*
X31619Y-320235D01*
X31175Y-320068D01*
X30605D01*
G01X31175D02*
X31555Y-319818D01*
X31872Y-319402D01*
X31999Y-318902D01*
X31872Y-318402D01*
X31555Y-317985D01*
X30985Y-317735D01*
X30415Y-317818D01*
X29845Y-318152D01*
G01X34629Y-320652D02*
X35072Y-320068D01*
X35452Y-319735D01*
X35959Y-319568D01*
X36402Y-319735D01*
X36719Y-320068D01*
X36972Y-320568D01*
X37035Y-321152D01*
X36972Y-321652D01*
X36719Y-322152D01*
X36339Y-322568D01*
X35895Y-322735D01*
X35389Y-322568D01*
X34945Y-322068D01*
X34692Y-321318D01*
X34629Y-320485D01*
X34755Y-319402D01*
X34945Y-318818D01*
X35262Y-318235D01*
X35705Y-317818D01*
X36149Y-317735D01*
X36592Y-317902D01*
X36909Y-318318D01*
G01X40932Y-322735D02*
Y-317735D01*
X40172Y-318735D01*
G01Y-322735D02*
X41692D01*
G01X46792D02*
Y-317735D01*
X44449Y-321318D01*
X47615D01*
G01X-129168Y-252735D02*
Y-327735D01*
X370832D01*
Y-252735D01*
X-129168D01*
G01X65832D02*
Y-327735D01*
G01Y-302735D02*
X168832D01*
Y-277735D01*
G01X65832D02*
X168832D01*
G01X176339Y-312735D02*
Y-307735D01*
X177605D01*
X178112Y-307985D01*
X178492Y-308318D01*
X178809Y-308818D01*
X179062Y-309402D01*
X179125Y-310235D01*
X179062Y-311068D01*
X178809Y-311652D01*
X178492Y-312152D01*
X178112Y-312485D01*
X177605Y-312735D01*
X176339D01*
G01X181249D02*
X182832Y-307735D01*
X184415Y-312735D01*
G01X183845Y-310985D02*
X181819D01*
G01X187932Y-307735D02*
Y-312735D01*
G01X186475Y-307735D02*
X189389D01*
G01X194299Y-312735D02*
X191765D01*
Y-307735D01*
X194299D01*
G01X193285Y-310152D02*
X191765D01*
G01X198132Y-312902D02*
X198005Y-312818D01*
Y-312652D01*
X198132Y-312568D01*
X198259Y-312652D01*
Y-312818D01*
X198132Y-312902D01*
G01Y-310652D02*
X198005Y-310568D01*
Y-310402D01*
X198132Y-310318D01*
X198259Y-310402D01*
Y-310568D01*
X198132Y-310652D01*
G01X170832Y-252735D02*
Y-327735D01*
G01X168832Y-252735D02*
Y-327735D01*
G01X170832Y-302735D02*
X370832D01*
G01X176465Y-287735D02*
Y-282735D01*
X177985D01*
X178492Y-282985D01*
X178872Y-283568D01*
X178999Y-284235D01*
X178872Y-284902D01*
X178555Y-285402D01*
X177985Y-285652D01*
X176465D01*
G01X181692Y-287902D02*
X183972Y-282735D01*
G01X186475Y-287735D02*
Y-282735D01*
X189389Y-287735D01*
Y-282735D01*
G01X193032Y-287902D02*
X192905Y-287818D01*
Y-287652D01*
X193032Y-287568D01*
X193159Y-287652D01*
Y-287818D01*
X193032Y-287902D01*
G01Y-285652D02*
X192905Y-285568D01*
Y-285402D01*
X193032Y-285318D01*
X193159Y-285402D01*
Y-285568D01*
X193032Y-285652D01*
G01X170832Y-277735D02*
X370832D01*
G01X176465Y-262735D02*
Y-257735D01*
X177985D01*
X178492Y-257985D01*
X178872Y-258568D01*
X178999Y-259235D01*
X178872Y-259902D01*
X178555Y-260402D01*
X177985Y-260652D01*
X176465D01*
G01X181565Y-262735D02*
Y-257735D01*
X183149D01*
X183655Y-257985D01*
X183972Y-258318D01*
X184099Y-258985D01*
X183972Y-259652D01*
X183592Y-260068D01*
X183149Y-260318D01*
X181565D01*
G01X183149D02*
X184099Y-262735D01*
G01X187932D02*
X187425Y-262652D01*
X186982Y-262318D01*
X186602Y-261818D01*
X186349Y-261235D01*
X186222Y-260568D01*
Y-259902D01*
X186349Y-259235D01*
X186602Y-258652D01*
X186982Y-258152D01*
X187425Y-257818D01*
X187932Y-257735D01*
X188439Y-257818D01*
X188882Y-258152D01*
X189262Y-258652D01*
X189515Y-259235D01*
X189642Y-259902D01*
Y-260568D01*
X189515Y-261235D01*
X189262Y-261818D01*
X188882Y-262318D01*
X188439Y-262652D01*
X187932Y-262735D01*
G01X191765Y-261735D02*
X192082Y-262235D01*
X192462Y-262568D01*
X192905Y-262735D01*
X193412Y-262568D01*
X193792Y-262235D01*
X194172Y-261735D01*
X194299Y-261068D01*
Y-257735D01*
G01X199399Y-262735D02*
X196865D01*
Y-257735D01*
X199399D01*
G01X198385Y-260152D02*
X196865D01*
G01X204625Y-258152D02*
X204245Y-257902D01*
X203802Y-257735D01*
X203295D01*
X202725Y-257985D01*
X202282Y-258402D01*
X201965Y-258902D01*
X201712Y-259735D01*
X201649Y-260485D01*
X201775Y-261235D01*
X201965Y-261735D01*
X202345Y-262235D01*
X202789Y-262568D01*
X203232Y-262735D01*
X203675D01*
X204119Y-262568D01*
X204499Y-262318D01*
X204815Y-261985D01*
G01X208332Y-257735D02*
Y-262735D01*
G01X206875Y-257735D02*
X209789D01*
G01X213432Y-262902D02*
X213305Y-262818D01*
Y-262652D01*
X213432Y-262568D01*
X213559Y-262652D01*
Y-262818D01*
X213432Y-262902D01*
G01Y-260652D02*
X213305Y-260568D01*
Y-260402D01*
X213432Y-260318D01*
X213559Y-260402D01*
Y-260568D01*
X213432Y-260652D01*
G01X283832Y-302735D02*
Y-327735D01*
G01X288465Y-305235D02*
Y-310235D01*
X290999D01*
G01X294072Y-305235D02*
X295592D01*
G01X294832D02*
Y-310235D01*
G01X294072D02*
X295592D01*
G01X300439Y-307568D02*
X300692Y-307318D01*
X300882Y-306902D01*
X301009Y-306318D01*
X300882Y-305818D01*
X300629Y-305485D01*
X300185Y-305235D01*
X298475D01*
Y-310235D01*
X300565D01*
X301009Y-309902D01*
X301262Y-309402D01*
X301389Y-308818D01*
X301262Y-308235D01*
X300882Y-307735D01*
X300439Y-307568D01*
X298475D01*
G01X305032Y-310402D02*
X304905Y-310318D01*
Y-310152D01*
X305032Y-310068D01*
X305159Y-310152D01*
Y-310318D01*
X305032Y-310402D01*
G01Y-308152D02*
X304905Y-308068D01*
Y-307902D01*
X305032Y-307818D01*
X305159Y-307902D01*
Y-308068D01*
X305032Y-308152D01*
G01X328832Y-302735D02*
Y-327735D01*
G01X332732Y-305235D02*
Y-310235D01*
G01X331275Y-305235D02*
X334189D01*
G01X337832Y-310235D02*
X337452Y-310152D01*
X337072Y-309818D01*
X336819Y-309235D01*
X336692Y-308568D01*
X336819Y-307902D01*
X337072Y-307318D01*
X337452Y-306985D01*
X337832Y-306902D01*
X338212Y-306985D01*
X338592Y-307318D01*
X338845Y-307902D01*
X338909Y-308568D01*
X338845Y-309235D01*
X338592Y-309818D01*
X338212Y-310152D01*
X337832Y-310235D01*
G01X342932D02*
X342552Y-310152D01*
X342172Y-309818D01*
X341919Y-309235D01*
X341792Y-308568D01*
X341919Y-307902D01*
X342172Y-307318D01*
X342552Y-306985D01*
X342932Y-306902D01*
X343312Y-306985D01*
X343692Y-307318D01*
X343945Y-307902D01*
X344009Y-308568D01*
X343945Y-309235D01*
X343692Y-309818D01*
X343312Y-310152D01*
X342932Y-310235D01*
G01X348032D02*
Y-305235D01*
G01X353132Y-310402D02*
X353005Y-310318D01*
Y-310152D01*
X353132Y-310068D01*
X353259Y-310152D01*
Y-310318D01*
X353132Y-310402D01*
G01Y-308152D02*
X353005Y-308068D01*
Y-307902D01*
X353132Y-307818D01*
X353259Y-307902D01*
Y-308068D01*
X353132Y-308152D01*
G01X328832Y-277735D02*
Y-302735D01*
G01X331465Y-285235D02*
Y-280235D01*
X333049D01*
X333555Y-280485D01*
X333872Y-280818D01*
X333999Y-281485D01*
X333872Y-282152D01*
X333492Y-282568D01*
X333049Y-282818D01*
X331465D01*
G01X333049D02*
X333999Y-285235D01*
G01X339099D02*
X336565D01*
Y-280235D01*
X339099D01*
G01X338085Y-282652D02*
X336565D01*
G01X341349Y-280235D02*
X342932Y-285235D01*
X344515Y-280235D01*
G01X348032Y-285402D02*
X347905Y-285318D01*
Y-285152D01*
X348032Y-285068D01*
X348159Y-285152D01*
Y-285318D01*
X348032Y-285402D01*
G01Y-283152D02*
X347905Y-283068D01*
Y-282902D01*
X348032Y-282818D01*
X348159Y-282902D01*
Y-283068D01*
X348032Y-283152D01*
G01X351592Y-329435D02*
X351672Y-329360D01*
X351732Y-329235D01*
X351772Y-329060D01*
X351732Y-328910D01*
X351652Y-328810D01*
X351512Y-328735D01*
X350972D01*
Y-330235D01*
X351632D01*
X351772Y-330135D01*
X351852Y-329985D01*
X351892Y-329810D01*
X351852Y-329635D01*
X351732Y-329485D01*
X351592Y-329435D01*
X350972D01*
G01X352992Y-330235D02*
Y-329235D01*
G01Y-329410D02*
X352912Y-329310D01*
X352792Y-329260D01*
X352652Y-329235D01*
X352512Y-329285D01*
X352392Y-329385D01*
X352312Y-329535D01*
X352272Y-329735D01*
X352312Y-329935D01*
X352392Y-330085D01*
X352512Y-330185D01*
X352652Y-330235D01*
X352792Y-330210D01*
X352912Y-330135D01*
X352992Y-330035D01*
G01X353532Y-330060D02*
X353632Y-330160D01*
X353772Y-330235D01*
X353892D01*
X354012Y-330185D01*
X354092Y-330110D01*
X354132Y-330010D01*
X354112Y-329860D01*
X354032Y-329785D01*
X353672Y-329635D01*
X353592Y-329460D01*
X353632Y-329335D01*
X353712Y-329260D01*
X353832Y-329235D01*
X353952Y-329260D01*
X354072Y-329335D01*
G01X354732Y-329560D02*
X355372D01*
X355312Y-329385D01*
X355212Y-329285D01*
X355072Y-329235D01*
X354932Y-329260D01*
X354812Y-329335D01*
X354732Y-329510D01*
X354692Y-329660D01*
Y-329810D01*
X354732Y-329960D01*
X354832Y-330110D01*
X354952Y-330210D01*
X355092Y-330235D01*
X355232Y-330185D01*
X355372Y-330035D01*
G01X355872Y-330235D02*
Y-328735D01*
G01Y-329485D02*
X355972Y-329335D01*
X356092Y-329260D01*
X356212Y-329235D01*
X356392Y-329285D01*
X356512Y-329385D01*
X356592Y-329560D01*
Y-329760D01*
X356552Y-329960D01*
X356472Y-330110D01*
X356332Y-330210D01*
X356212Y-330235D01*
X356092Y-330210D01*
X355972Y-330135D01*
X355872Y-330010D01*
G01X357432Y-330235D02*
X357312Y-330210D01*
X357192Y-330110D01*
X357112Y-329935D01*
X357072Y-329735D01*
X357112Y-329535D01*
X357192Y-329360D01*
X357312Y-329260D01*
X357432Y-329235D01*
X357552Y-329260D01*
X357672Y-329360D01*
X357752Y-329535D01*
X357772Y-329735D01*
X357752Y-329935D01*
X357672Y-330110D01*
X357552Y-330210D01*
X357432Y-330235D01*
G01X358992D02*
Y-329235D01*
G01Y-329410D02*
X358912Y-329310D01*
X358792Y-329260D01*
X358652Y-329235D01*
X358512Y-329285D01*
X358392Y-329385D01*
X358312Y-329535D01*
X358272Y-329735D01*
X358312Y-329935D01*
X358392Y-330085D01*
X358512Y-330185D01*
X358652Y-330235D01*
X358792Y-330210D01*
X358912Y-330135D01*
X358992Y-330035D01*
G01X359552Y-330235D02*
Y-329235D01*
G01Y-329435D02*
X359652Y-329335D01*
X359752Y-329260D01*
X359892Y-329235D01*
X359992Y-329260D01*
X360112Y-329335D01*
G01X361392Y-328735D02*
Y-330235D01*
G01Y-330010D02*
X361312Y-330135D01*
X361192Y-330210D01*
X361052Y-330235D01*
X360892Y-330185D01*
X360772Y-330060D01*
X360692Y-329910D01*
X360672Y-329735D01*
X360692Y-329560D01*
X360772Y-329410D01*
X360892Y-329285D01*
X361052Y-329235D01*
X361192Y-329260D01*
X361292Y-329310D01*
X361392Y-329410D01*
G01X363032Y-330235D02*
Y-328735D01*
X363532D01*
X363692Y-328810D01*
X363792Y-328910D01*
X363832Y-329110D01*
X363792Y-329310D01*
X363672Y-329435D01*
X363532Y-329510D01*
X363032D01*
G01X363532D02*
X363832Y-330235D01*
G01X364332Y-329560D02*
X364972D01*
X364912Y-329385D01*
X364812Y-329285D01*
X364672Y-329235D01*
X364532Y-329260D01*
X364412Y-329335D01*
X364332Y-329510D01*
X364292Y-329660D01*
Y-329810D01*
X364332Y-329960D01*
X364432Y-330110D01*
X364552Y-330210D01*
X364692Y-330235D01*
X364832Y-330185D01*
X364972Y-330035D01*
G01X365472Y-329235D02*
X365832Y-330235D01*
X366192Y-329235D01*
G01X367032Y-330285D02*
X366992Y-330260D01*
Y-330210D01*
X367032Y-330185D01*
X367072Y-330210D01*
Y-330260D01*
X367032Y-330285D01*
G01X368192Y-330235D02*
X368232Y-329910D01*
X368292Y-329635D01*
X368372Y-329385D01*
X368472Y-329110D01*
X368632Y-328735D01*
X367832D01*
G01X369592Y-329435D02*
X369672Y-329360D01*
X369732Y-329235D01*
X369772Y-329060D01*
X369732Y-328910D01*
X369652Y-328810D01*
X369512Y-328735D01*
X368972D01*
Y-330235D01*
X369632D01*
X369772Y-330135D01*
X369852Y-329985D01*
X369892Y-329810D01*
X369852Y-329635D01*
X369732Y-329485D01*
X369592Y-329435D01*
X368972D01*
G01X-247901Y-428634D02*
Y1008173D01*
X2091018D01*
Y-428634D01*
X-247901D01*
G01X-115095Y-307460D02*
X-115565Y-307145D01*
X-116113Y-306935D01*
X-116740D01*
X-117445Y-307250D01*
X-117993Y-307775D01*
X-118385Y-308405D01*
X-118698Y-309455D01*
X-118776Y-310400D01*
X-118620Y-311345D01*
X-118385Y-311975D01*
X-117915Y-312605D01*
X-117366Y-313025D01*
X-116818Y-313235D01*
X-116270D01*
X-115721Y-313025D01*
X-115251Y-312710D01*
X-114860Y-312290D01*
G01X-111458Y-306935D02*
X-109578D01*
G01X-110518D02*
Y-313235D01*
G01X-111458D02*
X-109578D01*
G01X-104218Y-306935D02*
Y-313235D01*
G01X-106020Y-306935D02*
X-102416D01*
G01X-97918Y-313235D02*
Y-310400D01*
X-99485Y-306935D01*
G01X-96351D02*
X-97918Y-310400D01*
G01X-87041Y-311975D02*
X-86571Y-312710D01*
X-85945Y-313130D01*
X-85240Y-313235D01*
X-84613Y-313130D01*
X-83986Y-312605D01*
X-83595Y-311975D01*
X-83516Y-311345D01*
X-83673Y-310610D01*
X-84221Y-310085D01*
X-84770Y-309875D01*
X-85475D01*
G01X-84770D02*
X-84300Y-309560D01*
X-83908Y-309035D01*
X-83751Y-308405D01*
X-83908Y-307775D01*
X-84300Y-307250D01*
X-85005Y-306935D01*
X-85710Y-307040D01*
X-86415Y-307460D01*
G01X-80741Y-311975D02*
X-80271Y-312710D01*
X-79645Y-313130D01*
X-78940Y-313235D01*
X-78313Y-313130D01*
X-77686Y-312605D01*
X-77295Y-311975D01*
X-77216Y-311345D01*
X-77373Y-310610D01*
X-77921Y-310085D01*
X-78470Y-309875D01*
X-79175D01*
G01X-78470D02*
X-78000Y-309560D01*
X-77608Y-309035D01*
X-77451Y-308405D01*
X-77608Y-307775D01*
X-78000Y-307250D01*
X-78705Y-306935D01*
X-79410Y-307040D01*
X-80115Y-307460D01*
G01X-74441Y-311975D02*
X-73971Y-312710D01*
X-73345Y-313130D01*
X-72640Y-313235D01*
X-72013Y-313130D01*
X-71386Y-312605D01*
X-70995Y-311975D01*
X-70916Y-311345D01*
X-71073Y-310610D01*
X-71621Y-310085D01*
X-72170Y-309875D01*
X-72875D01*
G01X-72170D02*
X-71700Y-309560D01*
X-71308Y-309035D01*
X-71151Y-308405D01*
X-71308Y-307775D01*
X-71700Y-307250D01*
X-72405Y-306935D01*
X-73110Y-307040D01*
X-73815Y-307460D01*
G01X-66575Y-313235D02*
X-66418Y-311870D01*
X-66183Y-310715D01*
X-65870Y-309665D01*
X-65478Y-308510D01*
X-64851Y-306935D01*
X-67985D01*
G01X-60275Y-313235D02*
X-60118Y-311870D01*
X-59883Y-310715D01*
X-59570Y-309665D01*
X-59178Y-308510D01*
X-58551Y-306935D01*
X-61685D01*
G01X-53975Y-314390D02*
X-53661Y-313025D01*
G01X-47518Y-306935D02*
Y-313235D01*
G01X-49320Y-306935D02*
X-45716D01*
G01X-43176Y-313235D02*
X-41218Y-306935D01*
X-39260Y-313235D01*
G01X-39965Y-311030D02*
X-42471D01*
G01X-35858Y-306935D02*
X-33978D01*
G01X-34918D02*
Y-313235D01*
G01X-35858D02*
X-33978D01*
G01X-30968Y-306935D02*
X-29871Y-313235D01*
X-28618Y-306935D01*
X-27365Y-313235D01*
X-26268Y-306935D01*
G01X-24276Y-313235D02*
X-22318Y-306935D01*
X-20360Y-313235D01*
G01X-21065Y-311030D02*
X-23571D01*
G01X-17820Y-313235D02*
Y-306935D01*
X-14216Y-313235D01*
Y-306935D01*
G01X-3810Y-315335D02*
X-4593Y-314285D01*
X-4985Y-313235D01*
Y-309035D01*
X-4593Y-307985D01*
X-3810Y-306935D01*
G01X7615Y-313235D02*
Y-306935D01*
X9574D01*
X10200Y-307250D01*
X10592Y-307670D01*
X10749Y-308510D01*
X10592Y-309350D01*
X10122Y-309875D01*
X9574Y-310190D01*
X7615D01*
G01X9574D02*
X10749Y-313235D01*
G01X15482Y-313445D02*
X15325Y-313340D01*
Y-313130D01*
X15482Y-313025D01*
X15639Y-313130D01*
Y-313340D01*
X15482Y-313445D01*
G01X21782Y-313235D02*
X21155Y-313130D01*
X20607Y-312710D01*
X20137Y-312080D01*
X19824Y-311345D01*
X19667Y-310505D01*
Y-309665D01*
X19824Y-308825D01*
X20137Y-308090D01*
X20607Y-307460D01*
X21155Y-307040D01*
X21782Y-306935D01*
X22409Y-307040D01*
X22957Y-307460D01*
X23427Y-308090D01*
X23740Y-308825D01*
X23897Y-309665D01*
Y-310505D01*
X23740Y-311345D01*
X23427Y-312080D01*
X22957Y-312710D01*
X22409Y-313130D01*
X21782Y-313235D01*
G01X28082Y-313445D02*
X27925Y-313340D01*
Y-313130D01*
X28082Y-313025D01*
X28239Y-313130D01*
Y-313340D01*
X28082Y-313445D01*
G01X36105Y-307460D02*
X35635Y-307145D01*
X35087Y-306935D01*
X34460D01*
X33755Y-307250D01*
X33207Y-307775D01*
X32815Y-308405D01*
X32502Y-309455D01*
X32424Y-310400D01*
X32580Y-311345D01*
X32815Y-311975D01*
X33285Y-312605D01*
X33834Y-313025D01*
X34382Y-313235D01*
X34930D01*
X35479Y-313025D01*
X35949Y-312710D01*
X36340Y-312290D01*
G01X40682Y-313445D02*
X40525Y-313340D01*
Y-313130D01*
X40682Y-313025D01*
X40839Y-313130D01*
Y-313340D01*
X40682Y-313445D01*
G01X47374Y-315335D02*
X48157Y-314285D01*
X48549Y-313235D01*
Y-309035D01*
X48157Y-307985D01*
X47374Y-306935D01*
G01X-118620Y-293235D02*
Y-286935D01*
X-115016Y-293235D01*
Y-286935D01*
G01X-110518Y-293235D02*
X-111145Y-293130D01*
X-111693Y-292710D01*
X-112163Y-292080D01*
X-112476Y-291345D01*
X-112633Y-290505D01*
Y-289665D01*
X-112476Y-288825D01*
X-112163Y-288090D01*
X-111693Y-287460D01*
X-111145Y-287040D01*
X-110518Y-286935D01*
X-109891Y-287040D01*
X-109343Y-287460D01*
X-108873Y-288090D01*
X-108560Y-288825D01*
X-108403Y-289665D01*
Y-290505D01*
X-108560Y-291345D01*
X-108873Y-292080D01*
X-109343Y-292710D01*
X-109891Y-293130D01*
X-110518Y-293235D01*
G01X-104218Y-293445D02*
X-104375Y-293340D01*
Y-293130D01*
X-104218Y-293025D01*
X-104061Y-293130D01*
Y-293340D01*
X-104218Y-293445D01*
G01X-99406Y-287985D02*
X-98936Y-287355D01*
X-98388Y-287040D01*
X-97761Y-286935D01*
X-96978Y-287145D01*
X-96430Y-287670D01*
X-96273Y-288300D01*
X-96351Y-288930D01*
X-96665Y-289455D01*
X-98231Y-290505D01*
X-98936Y-291240D01*
X-99406Y-292290D01*
X-99563Y-293235D01*
X-96273D01*
G01X-91618D02*
Y-286935D01*
X-92558Y-288195D01*
G01Y-293235D02*
X-90678D01*
G01X-85318D02*
Y-286935D01*
X-86258Y-288195D01*
G01Y-293235D02*
X-84378D01*
G01X-79175Y-294390D02*
X-78861Y-293025D01*
G01X-75068Y-286935D02*
X-73971Y-293235D01*
X-72718Y-286935D01*
X-71465Y-293235D01*
X-70368Y-286935D01*
G01X-64851Y-293235D02*
X-67985D01*
Y-286935D01*
X-64851D01*
G01X-66105Y-289980D02*
X-67985D01*
G01X-61920Y-293235D02*
Y-286935D01*
X-58316Y-293235D01*
Y-286935D01*
G01X-55463Y-293235D02*
Y-286935D01*
G01X-52173D02*
Y-293235D01*
G01Y-290085D02*
X-55463D01*
G01X-49241Y-286935D02*
Y-291450D01*
X-48928Y-292395D01*
X-48301Y-293025D01*
X-47518Y-293235D01*
X-46735Y-293025D01*
X-46108Y-292395D01*
X-45795Y-291450D01*
Y-286935D01*
G01X-43176Y-293235D02*
X-41218Y-286935D01*
X-39260Y-293235D01*
G01X-39965Y-291030D02*
X-42471D01*
G01X-30106Y-287985D02*
X-29636Y-287355D01*
X-29088Y-287040D01*
X-28461Y-286935D01*
X-27678Y-287145D01*
X-27130Y-287670D01*
X-26973Y-288300D01*
X-27051Y-288930D01*
X-27365Y-289455D01*
X-28931Y-290505D01*
X-29636Y-291240D01*
X-30106Y-292290D01*
X-30263Y-293235D01*
X-26973D01*
G01X-24120D02*
Y-286935D01*
X-20516Y-293235D01*
Y-286935D01*
G01X-17741Y-293235D02*
Y-286935D01*
X-16175D01*
X-15548Y-287250D01*
X-15078Y-287670D01*
X-14686Y-288300D01*
X-14373Y-289035D01*
X-14295Y-290085D01*
X-14373Y-291135D01*
X-14686Y-291870D01*
X-15078Y-292500D01*
X-15548Y-292920D01*
X-16175Y-293235D01*
X-17741D01*
G01X-4985D02*
Y-286935D01*
X-3026D01*
X-2400Y-287250D01*
X-2008Y-287670D01*
X-1851Y-288510D01*
X-2008Y-289350D01*
X-2478Y-289875D01*
X-3026Y-290190D01*
X-4985D01*
G01X-3026D02*
X-1851Y-293235D01*
G01X1159D02*
Y-286935D01*
X2725D01*
X3352Y-287250D01*
X3822Y-287670D01*
X4214Y-288300D01*
X4527Y-289035D01*
X4605Y-290085D01*
X4527Y-291135D01*
X4214Y-291870D01*
X3822Y-292500D01*
X3352Y-292920D01*
X2725Y-293235D01*
X1159D01*
G01X9182Y-293445D02*
X9025Y-293340D01*
Y-293130D01*
X9182Y-293025D01*
X9339Y-293130D01*
Y-293340D01*
X9182Y-293445D01*
G01X-116348Y-300085D02*
X-114781D01*
Y-301975D01*
X-115251Y-302605D01*
X-115800Y-303025D01*
X-116583Y-303235D01*
X-117366Y-303025D01*
X-117915Y-302605D01*
X-118385Y-301975D01*
X-118698Y-301240D01*
X-118855Y-300400D01*
Y-299665D01*
X-118698Y-299035D01*
X-118385Y-298300D01*
X-117915Y-297670D01*
X-117445Y-297250D01*
X-116818Y-296935D01*
X-116270D01*
X-115643Y-297145D01*
X-115173Y-297565D01*
G01X-112241Y-296935D02*
Y-301450D01*
X-111928Y-302395D01*
X-111301Y-303025D01*
X-110518Y-303235D01*
X-109735Y-303025D01*
X-109108Y-302395D01*
X-108795Y-301450D01*
Y-296935D01*
G01X-105158D02*
X-103278D01*
G01X-104218D02*
Y-303235D01*
G01X-105158D02*
X-103278D01*
G01X-99563Y-302395D02*
X-98936Y-302920D01*
X-98231Y-303235D01*
X-97605D01*
X-96978Y-302920D01*
X-96508Y-302395D01*
X-96273Y-301660D01*
X-96430Y-300925D01*
X-96821Y-300295D01*
X-97526Y-299875D01*
X-98466Y-299665D01*
X-99015Y-299245D01*
X-99250Y-298510D01*
X-99093Y-297775D01*
X-98701Y-297250D01*
X-98153Y-296935D01*
X-97605D01*
X-97056Y-297145D01*
X-96586Y-297670D01*
G01X-93263Y-303235D02*
Y-296935D01*
G01X-89973D02*
Y-303235D01*
G01Y-300085D02*
X-93263D01*
G01X-87276Y-303235D02*
X-85318Y-296935D01*
X-83360Y-303235D01*
G01X-84065Y-301030D02*
X-86571D01*
G01X-80820Y-303235D02*
Y-296935D01*
X-77216Y-303235D01*
Y-296935D01*
G01X-68141Y-303235D02*
Y-296935D01*
X-66575D01*
X-65948Y-297250D01*
X-65478Y-297670D01*
X-65086Y-298300D01*
X-64773Y-299035D01*
X-64695Y-300085D01*
X-64773Y-301135D01*
X-65086Y-301870D01*
X-65478Y-302500D01*
X-65948Y-302920D01*
X-66575Y-303235D01*
X-68141D01*
G01X-61058Y-296935D02*
X-59178D01*
G01X-60118D02*
Y-303235D01*
G01X-61058D02*
X-59178D01*
G01X-55463Y-302395D02*
X-54836Y-302920D01*
X-54131Y-303235D01*
X-53505D01*
X-52878Y-302920D01*
X-52408Y-302395D01*
X-52173Y-301660D01*
X-52330Y-300925D01*
X-52721Y-300295D01*
X-53426Y-299875D01*
X-54366Y-299665D01*
X-54915Y-299245D01*
X-55150Y-298510D01*
X-54993Y-297775D01*
X-54601Y-297250D01*
X-54053Y-296935D01*
X-53505D01*
X-52956Y-297145D01*
X-52486Y-297670D01*
G01X-47518Y-296935D02*
Y-303235D01*
G01X-49320Y-296935D02*
X-45716D01*
G01X-41218Y-303445D02*
X-41375Y-303340D01*
Y-303130D01*
X-41218Y-303025D01*
X-41061Y-303130D01*
Y-303340D01*
X-41218Y-303445D01*
G01X-35075Y-304390D02*
X-34761Y-303025D01*
G01X-28618Y-296935D02*
Y-303235D01*
G01X-30420Y-296935D02*
X-26816D01*
G01X-24276Y-303235D02*
X-22318Y-296935D01*
X-20360Y-303235D01*
G01X-21065Y-301030D02*
X-23571D01*
G01X-16018Y-303235D02*
X-16645Y-303130D01*
X-17193Y-302710D01*
X-17663Y-302080D01*
X-17976Y-301345D01*
X-18133Y-300505D01*
Y-299665D01*
X-17976Y-298825D01*
X-17663Y-298090D01*
X-17193Y-297460D01*
X-16645Y-297040D01*
X-16018Y-296935D01*
X-15391Y-297040D01*
X-14843Y-297460D01*
X-14373Y-298090D01*
X-14060Y-298825D01*
X-13903Y-299665D01*
Y-300505D01*
X-14060Y-301345D01*
X-14373Y-302080D01*
X-14843Y-302710D01*
X-15391Y-303130D01*
X-16018Y-303235D01*
G01X-9718D02*
Y-300400D01*
X-11285Y-296935D01*
G01X-8151D02*
X-9718Y-300400D01*
G01X-5141Y-296935D02*
Y-301450D01*
X-4828Y-302395D01*
X-4201Y-303025D01*
X-3418Y-303235D01*
X-2635Y-303025D01*
X-2008Y-302395D01*
X-1695Y-301450D01*
Y-296935D01*
G01X924Y-303235D02*
X2882Y-296935D01*
X4840Y-303235D01*
G01X4135Y-301030D02*
X1629D01*
G01X7380Y-303235D02*
Y-296935D01*
X10984Y-303235D01*
Y-296935D01*
G01X-94518Y-282535D02*
X-97038Y-282118D01*
X-99243Y-280452D01*
X-101133Y-277952D01*
X-102393Y-275035D01*
X-103023Y-271702D01*
Y-268368D01*
X-102393Y-265035D01*
X-101133Y-262118D01*
X-99243Y-259619D01*
X-97038Y-257952D01*
X-94518Y-257535D01*
X-91998Y-257952D01*
X-89793Y-259619D01*
X-87903Y-262118D01*
X-86643Y-265035D01*
X-86013Y-268368D01*
Y-271702D01*
X-86643Y-275035D01*
X-87903Y-277952D01*
X-89793Y-280452D01*
X-91998Y-282118D01*
X-94518Y-282535D01*
G01X-91998Y-275868D02*
X-88218Y-282535D01*
G01X-74673Y-265869D02*
Y-277535D01*
X-73413Y-280452D01*
X-71523Y-282118D01*
X-69318Y-282535D01*
X-67113Y-282118D01*
X-65223Y-280452D01*
X-63963Y-277535D01*
G01Y-282535D02*
Y-265869D01*
G01X-38448Y-282535D02*
Y-265869D01*
G01Y-268785D02*
X-39708Y-267119D01*
X-41598Y-266285D01*
X-43803Y-265869D01*
X-46008Y-266702D01*
X-47898Y-268368D01*
X-49158Y-270869D01*
X-49788Y-274202D01*
X-49158Y-277535D01*
X-47898Y-280036D01*
X-46008Y-281702D01*
X-43803Y-282535D01*
X-41598Y-282118D01*
X-39708Y-280869D01*
X-38448Y-279202D01*
G01X-24273Y-282535D02*
Y-265869D01*
G01Y-270035D02*
X-23013Y-267952D01*
X-21123Y-266285D01*
X-18603Y-265869D01*
X-16398Y-266285D01*
X-14508Y-267952D01*
X-13563Y-270869D01*
Y-282535D01*
G01X6282Y-257535D02*
Y-282535D01*
G01X1872Y-265869D02*
X10692D01*
G01X37152Y-282535D02*
Y-265869D01*
G01Y-268785D02*
X35892Y-267119D01*
X34002Y-266285D01*
X31797Y-265869D01*
X29592Y-266702D01*
X27702Y-268368D01*
X26442Y-270869D01*
X25812Y-274202D01*
X26442Y-277535D01*
X27702Y-280036D01*
X29592Y-281702D01*
X31797Y-282535D01*
X34002Y-282118D01*
X35892Y-280869D01*
X37152Y-279202D01*
G01X76832Y-262235D02*
Y-270235D01*
X80832D01*
G01X88632D02*
Y-264902D01*
G01Y-265835D02*
X88232Y-265302D01*
X87632Y-265035D01*
X86932Y-264902D01*
X86232Y-265168D01*
X85632Y-265702D01*
X85232Y-266502D01*
X85032Y-267568D01*
X85232Y-268635D01*
X85632Y-269435D01*
X86232Y-269968D01*
X86932Y-270235D01*
X87632Y-270102D01*
X88232Y-269702D01*
X88632Y-269169D01*
G01X92732Y-272635D02*
X93332Y-272902D01*
X94132Y-272635D01*
X94632Y-272102D01*
X95032Y-271435D01*
X95632Y-269302D01*
X96932Y-264902D01*
G01X93732D02*
X95632Y-269302D01*
G01X101332Y-266635D02*
X104532D01*
X104232Y-265702D01*
X103732Y-265168D01*
X103032Y-264902D01*
X102332Y-265035D01*
X101732Y-265435D01*
X101332Y-266368D01*
X101132Y-267169D01*
Y-267968D01*
X101332Y-268768D01*
X101832Y-269568D01*
X102432Y-270102D01*
X103132Y-270235D01*
X103832Y-269968D01*
X104532Y-269169D01*
G01X109432Y-270235D02*
Y-264902D01*
G01Y-265968D02*
X109932Y-265435D01*
X110432Y-265035D01*
X111132Y-264902D01*
X111632Y-265035D01*
X112232Y-265435D01*
G01X95532Y-320235D02*
Y-312235D01*
X100132Y-320235D01*
Y-312235D01*
G01X105832Y-314902D02*
Y-320235D01*
G01Y-312768D02*
X105632Y-312635D01*
Y-312368D01*
X105832Y-312235D01*
X106032Y-312368D01*
Y-312635D01*
X105832Y-312768D01*
G01X112132Y-320235D02*
Y-314902D01*
G01Y-316235D02*
X112532Y-315568D01*
X113132Y-315035D01*
X113932Y-314902D01*
X114632Y-315035D01*
X115232Y-315568D01*
X115532Y-316502D01*
Y-320235D01*
G01X123632D02*
Y-314902D01*
G01Y-315835D02*
X123232Y-315302D01*
X122632Y-315035D01*
X121932Y-314902D01*
X121232Y-315168D01*
X120632Y-315702D01*
X120232Y-316502D01*
X120032Y-317568D01*
X120232Y-318635D01*
X120632Y-319435D01*
X121232Y-319968D01*
X121932Y-320235D01*
X122632Y-320102D01*
X123232Y-319702D01*
X123632Y-319169D01*
G01X105932Y-291235D02*
X107932D01*
Y-293635D01*
X107332Y-294435D01*
X106632Y-294968D01*
X105632Y-295235D01*
X104632Y-294968D01*
X103932Y-294435D01*
X103332Y-293635D01*
X102932Y-292702D01*
X102732Y-291635D01*
Y-290702D01*
X102932Y-289902D01*
X103332Y-288968D01*
X103932Y-288168D01*
X104532Y-287635D01*
X105332Y-287235D01*
X106032D01*
X106832Y-287502D01*
X107432Y-288035D01*
G01X111032Y-295235D02*
Y-287235D01*
X115632Y-295235D01*
Y-287235D01*
G01X119132Y-295235D02*
Y-287235D01*
X121132D01*
X121932Y-287635D01*
X122532Y-288168D01*
X123032Y-288968D01*
X123432Y-289902D01*
X123532Y-291235D01*
X123432Y-292568D01*
X123032Y-293502D01*
X122532Y-294302D01*
X121932Y-294835D01*
X121132Y-295235D01*
X119132D01*
G01X128432Y-263568D02*
X129032Y-262768D01*
X129732Y-262368D01*
X130532Y-262235D01*
X131532Y-262502D01*
X132232Y-263168D01*
X132432Y-263968D01*
X132332Y-264769D01*
X131932Y-265435D01*
X129932Y-266768D01*
X129032Y-267702D01*
X128432Y-269035D01*
X128232Y-270235D01*
X132432D01*
G01X203432Y-313568D02*
X204032Y-312768D01*
X204732Y-312368D01*
X205532Y-312235D01*
X206532Y-312502D01*
X207232Y-313168D01*
X207432Y-313968D01*
X207332Y-314769D01*
X206932Y-315435D01*
X204932Y-316768D01*
X204032Y-317702D01*
X203432Y-319035D01*
X203232Y-320235D01*
X207432D01*
G01X213332Y-312235D02*
X212532Y-312502D01*
X211932Y-313168D01*
X211532Y-313968D01*
X211232Y-315035D01*
X211132Y-316235D01*
X211232Y-317435D01*
X211532Y-318502D01*
X211932Y-319302D01*
X212532Y-319968D01*
X213332Y-320235D01*
X214132Y-319968D01*
X214732Y-319302D01*
X215132Y-318502D01*
X215432Y-317435D01*
X215532Y-316235D01*
X215432Y-315035D01*
X215132Y-313968D01*
X214732Y-313168D01*
X214132Y-312502D01*
X213332Y-312235D01*
G01X219432Y-313568D02*
X220032Y-312768D01*
X220732Y-312368D01*
X221532Y-312235D01*
X222532Y-312502D01*
X223232Y-313168D01*
X223432Y-313968D01*
X223332Y-314769D01*
X222932Y-315435D01*
X220932Y-316768D01*
X220032Y-317702D01*
X219432Y-319035D01*
X219232Y-320235D01*
X223432D01*
G01X227432Y-313568D02*
X228032Y-312768D01*
X228732Y-312368D01*
X229532Y-312235D01*
X230532Y-312502D01*
X231232Y-313168D01*
X231432Y-313968D01*
X231332Y-314769D01*
X230932Y-315435D01*
X228932Y-316768D01*
X228032Y-317702D01*
X227432Y-319035D01*
X227232Y-320235D01*
X231432D01*
G01X235532Y-320502D02*
X239132Y-312235D01*
G01X245332Y-320235D02*
Y-312235D01*
X244132Y-313835D01*
G01Y-320235D02*
X246532D01*
G01X251432Y-313568D02*
X252032Y-312768D01*
X252732Y-312368D01*
X253532Y-312235D01*
X254532Y-312502D01*
X255232Y-313168D01*
X255432Y-313968D01*
X255332Y-314769D01*
X254932Y-315435D01*
X252932Y-316768D01*
X252032Y-317702D01*
X251432Y-319035D01*
X251232Y-320235D01*
X255432D01*
G01X259532Y-320502D02*
X263132Y-312235D01*
G01X269332D02*
X268532Y-312502D01*
X267932Y-313168D01*
X267532Y-313968D01*
X267232Y-315035D01*
X267132Y-316235D01*
X267232Y-317435D01*
X267532Y-318502D01*
X267932Y-319302D01*
X268532Y-319968D01*
X269332Y-320235D01*
X270132Y-319968D01*
X270732Y-319302D01*
X271132Y-318502D01*
X271432Y-317435D01*
X271532Y-316235D01*
X271432Y-315035D01*
X271132Y-313968D01*
X270732Y-313168D01*
X270132Y-312502D01*
X269332Y-312235D01*
G01X275632Y-319302D02*
X276332Y-319968D01*
X277132Y-320235D01*
X277932Y-319968D01*
X278632Y-319169D01*
X279132Y-317968D01*
X279332Y-316768D01*
Y-315302D01*
X279132Y-314102D01*
X278632Y-313035D01*
X278032Y-312502D01*
X277332Y-312235D01*
X276532Y-312502D01*
X275932Y-313035D01*
X275532Y-313835D01*
X275332Y-314902D01*
X275532Y-315835D01*
X276032Y-316768D01*
X276632Y-317302D01*
X277332Y-317435D01*
X278132Y-317169D01*
X278732Y-316502D01*
X279332Y-315302D01*
G01X205632Y-295235D02*
Y-287235D01*
X207632D01*
X208432Y-287635D01*
X209032Y-288168D01*
X209532Y-288968D01*
X209932Y-289902D01*
X210032Y-291235D01*
X209932Y-292568D01*
X209532Y-293502D01*
X209032Y-294302D01*
X208432Y-294835D01*
X207632Y-295235D01*
X205632D01*
G01X213332D02*
X215832Y-287235D01*
X218332Y-295235D01*
G01X217432Y-292435D02*
X214232D01*
G01X223832Y-287235D02*
X223032Y-287502D01*
X222432Y-288168D01*
X222032Y-288968D01*
X221732Y-290035D01*
X221632Y-291235D01*
X221732Y-292435D01*
X222032Y-293502D01*
X222432Y-294302D01*
X223032Y-294968D01*
X223832Y-295235D01*
X224632Y-294968D01*
X225232Y-294302D01*
X225632Y-293502D01*
X225932Y-292435D01*
X226032Y-291235D01*
X225932Y-290035D01*
X225632Y-288968D01*
X225232Y-288168D01*
X224632Y-287502D01*
X223832Y-287235D01*
G01X229932Y-295235D02*
Y-287235D01*
X233732D01*
G01X232332Y-291102D02*
X229932D01*
G01X239832Y-287235D02*
X239032Y-287502D01*
X238432Y-288168D01*
X238032Y-288968D01*
X237732Y-290035D01*
X237632Y-291235D01*
X237732Y-292435D01*
X238032Y-293502D01*
X238432Y-294302D01*
X239032Y-294968D01*
X239832Y-295235D01*
X240632Y-294968D01*
X241232Y-294302D01*
X241632Y-293502D01*
X241932Y-292435D01*
X242032Y-291235D01*
X241932Y-290035D01*
X241632Y-288968D01*
X241232Y-288168D01*
X240632Y-287502D01*
X239832Y-287235D01*
G01X247832D02*
Y-295235D01*
G01X245532Y-287235D02*
X250132D01*
G01X255832Y-295235D02*
Y-291635D01*
X253832Y-287235D01*
G01X257832D02*
X255832Y-291635D01*
G01X264632Y-290968D02*
X265032Y-290568D01*
X265332Y-289902D01*
X265532Y-288968D01*
X265332Y-288168D01*
X264932Y-287635D01*
X264232Y-287235D01*
X261532D01*
Y-295235D01*
X264832D01*
X265532Y-294702D01*
X265932Y-293902D01*
X266132Y-292968D01*
X265932Y-292035D01*
X265332Y-291235D01*
X264632Y-290968D01*
X261532D01*
G01X273032Y-295235D02*
Y-287235D01*
X269332Y-292968D01*
X274332D01*
G01X277632Y-295235D02*
Y-287235D01*
X279632D01*
X280432Y-287635D01*
X281032Y-288168D01*
X281532Y-288968D01*
X281932Y-289902D01*
X282032Y-291235D01*
X281932Y-292568D01*
X281532Y-293502D01*
X281032Y-294302D01*
X280432Y-294835D01*
X279632Y-295235D01*
X277632D01*
G01X287832Y-287235D02*
X287032Y-287502D01*
X286432Y-288168D01*
X286032Y-288968D01*
X285732Y-290035D01*
X285632Y-291235D01*
X285732Y-292435D01*
X286032Y-293502D01*
X286432Y-294302D01*
X287032Y-294968D01*
X287832Y-295235D01*
X288632Y-294968D01*
X289232Y-294302D01*
X289632Y-293502D01*
X289932Y-292435D01*
X290032Y-291235D01*
X289932Y-290035D01*
X289632Y-288968D01*
X289232Y-288168D01*
X288632Y-287502D01*
X287832Y-287235D01*
G01X233432Y-270235D02*
Y-262235D01*
X237232D01*
G01X235832Y-266102D02*
X233432D01*
G01X243332Y-262235D02*
X242532Y-262502D01*
X241932Y-263168D01*
X241532Y-263968D01*
X241232Y-265035D01*
X241132Y-266235D01*
X241232Y-267435D01*
X241532Y-268502D01*
X241932Y-269302D01*
X242532Y-269968D01*
X243332Y-270235D01*
X244132Y-269968D01*
X244732Y-269302D01*
X245132Y-268502D01*
X245432Y-267435D01*
X245532Y-266235D01*
X245432Y-265035D01*
X245132Y-263968D01*
X244732Y-263168D01*
X244132Y-262502D01*
X243332Y-262235D01*
G01X251332D02*
Y-270235D01*
G01X249032Y-262235D02*
X253632D01*
G01X256332Y-272902D02*
X262332D01*
G01X265332Y-270235D02*
Y-262235D01*
X267732D01*
X268532Y-262635D01*
X269132Y-263568D01*
X269332Y-264635D01*
X269132Y-265702D01*
X268632Y-266502D01*
X267732Y-266902D01*
X265332D01*
G01X272832Y-270235D02*
X275332Y-262235D01*
X277832Y-270235D01*
G01X276932Y-267435D02*
X273732D01*
G01X281032Y-270235D02*
Y-262235D01*
X285632Y-270235D01*
Y-262235D01*
G01X293332Y-270235D02*
X289332D01*
Y-262235D01*
X293332D01*
G01X291732Y-266102D02*
X289332D01*
G01X297332Y-262235D02*
Y-270235D01*
X301332D01*
G01X304332Y-272902D02*
X310332D01*
G01X316132Y-265968D02*
X316532Y-265568D01*
X316832Y-264902D01*
X317032Y-263968D01*
X316832Y-263168D01*
X316432Y-262635D01*
X315732Y-262235D01*
X313032D01*
Y-270235D01*
X316332D01*
X317032Y-269702D01*
X317432Y-268902D01*
X317632Y-267968D01*
X317432Y-267035D01*
X316832Y-266235D01*
X316132Y-265968D01*
X313032D01*
G01X321132Y-270235D02*
Y-262235D01*
X323132D01*
X323932Y-262635D01*
X324532Y-263168D01*
X325032Y-263968D01*
X325432Y-264902D01*
X325532Y-266235D01*
X325432Y-267568D01*
X325032Y-268502D01*
X324532Y-269302D01*
X323932Y-269835D01*
X323132Y-270235D01*
X321132D01*
G01X291832Y-323235D02*
Y-315235D01*
X290632Y-316835D01*
G01Y-323235D02*
X293032D01*
G01X297932Y-319902D02*
X298632Y-318968D01*
X299232Y-318435D01*
X300032Y-318168D01*
X300732Y-318435D01*
X301232Y-318968D01*
X301632Y-319768D01*
X301732Y-320702D01*
X301632Y-321502D01*
X301232Y-322302D01*
X300632Y-322968D01*
X299932Y-323235D01*
X299132Y-322968D01*
X298432Y-322169D01*
X298032Y-320968D01*
X297932Y-319635D01*
X298132Y-317902D01*
X298432Y-316968D01*
X298932Y-316035D01*
X299632Y-315368D01*
X300332Y-315235D01*
X301032Y-315502D01*
X301532Y-316168D01*
G01X307832Y-323502D02*
X307632Y-323368D01*
Y-323102D01*
X307832Y-322968D01*
X308032Y-323102D01*
Y-323368D01*
X307832Y-323502D01*
G01X313932Y-319902D02*
X314632Y-318968D01*
X315232Y-318435D01*
X316032Y-318168D01*
X316732Y-318435D01*
X317232Y-318968D01*
X317632Y-319768D01*
X317732Y-320702D01*
X317632Y-321502D01*
X317232Y-322302D01*
X316632Y-322968D01*
X315932Y-323235D01*
X315132Y-322968D01*
X314432Y-322169D01*
X314032Y-320968D01*
X313932Y-319635D01*
X314132Y-317902D01*
X314432Y-316968D01*
X314932Y-316035D01*
X315632Y-315368D01*
X316332Y-315235D01*
X317032Y-315502D01*
X317532Y-316168D01*
G01X336832Y-323235D02*
Y-315235D01*
X335632Y-316835D01*
G01Y-323235D02*
X338032D01*
G01X344632D02*
X344832Y-321502D01*
X345132Y-320035D01*
X345532Y-318702D01*
X346032Y-317235D01*
X346832Y-315235D01*
X342832D01*
G01X352832Y-323502D02*
X352632Y-323368D01*
Y-323102D01*
X352832Y-322968D01*
X353032Y-323102D01*
Y-323368D01*
X352832Y-323502D01*
G01X358932Y-316568D02*
X359532Y-315768D01*
X360232Y-315368D01*
X361032Y-315235D01*
X362032Y-315502D01*
X362732Y-316168D01*
X362932Y-316968D01*
X362832Y-317769D01*
X362432Y-318435D01*
X360432Y-319768D01*
X359532Y-320702D01*
X358932Y-322035D01*
X358732Y-323235D01*
X362932D01*
G01X356632Y-298235D02*
Y-290235D01*
X358632D01*
X359432Y-290635D01*
X360032Y-291168D01*
X360532Y-291968D01*
X360932Y-292902D01*
X361032Y-294235D01*
X360932Y-295568D01*
X360532Y-296502D01*
X360032Y-297302D01*
X359432Y-297835D01*
X358632Y-298235D01*
X356632D01*
M02*
